G04 ================== begin FILE IDENTIFICATION RECORD ==================*
G04 Layout Name:  t6m_pdb_d_0928_1400_274.brd*
G04 Film Name:    in2*
G04 File Format:  Gerber RS274X*
G04 File Origin:  Cadence Allegro 16.3-S048*
G04 Origin Date:  Tue Nov 26 11:01:51 2013*
G04 *
G04 Layer:  DRAWING FORMAT/TITLE_BLOCK*
G04 Layer:  VIA CLASS/IN2*
G04 Layer:  PIN/IN2*
G04 Layer:  MANUFACTURING/PHOTOPLOT_OUTLINE*
G04 Layer:  ETCH/IN2*
G04 Layer:  DRAWING FORMAT/TITLE_DATA_IN2*
G04 *
G04 Offset:    (0.00 0.00)*
G04 Mirror:    No*
G04 Mode:      Positive*
G04 Rotation:  0*
G04 FullContactRelief:  No*
G04 UndefLineWidth:     6.00*
G04 ================== end FILE IDENTIFICATION RECORD ====================*
%FSLAX25Y25*MOIN*%
%IR0*IPPOS*OFA0.00000B0.00000*MIA0B0*SFA1.00000B1.00000*%
%ADD10C,.02*%
%ADD14C,.04*%
%ADD13C,.06*%
%ADD17C,.046*%
%ADD16C,.064*%
%ADD11C,.055*%
%ADD12C,.093*%
%ADD15C,.077*%
%ADD18C,.018*%
%ADD19C,.005*%
%ADD20C,.006*%
%ADD30C,.03004*%
%ADD21C,.05004*%
%ADD32C,.06204*%
%ADD34C,.09006*%
%ADD27C,.05604*%
%ADD23C,.06504*%
%ADD22C,.07404*%
%ADD31C,.08704*%
%ADD35C,.10504*%
%ADD24C,.40406*%
%ADD37C,.13236*%
%ADD36C,.23506*%
%ADD29C,.13238*%
%ADD25C,.16406*%
%ADD28C,.13266*%
%ADD33C,.15806*%
%ADD26C,.35606*%
G75*
%LPD*%
G75*
G36*
G01X104331Y2004D02*
G02X100429Y5906I0J3902D01*
G01Y9843D01*
G03X92520Y17752I-7909J0D01*
G01X5906D01*
G02X2004Y21654I0J3902D01*
G01Y521639D01*
X4151D01*
Y534230D01*
X2004D01*
Y2064961D01*
G02X5905Y2068862I3901J0D01*
G01X92520D01*
G03X100429Y2076772I0J7909D01*
G01Y2080709D01*
G02X104331Y2084610I3902J-1D01*
G01X397638D01*
G02X403508Y2078740I0J-5870D01*
G01Y7874D01*
G02X397638Y2004I-5870J0D01*
G01X104331D01*
G37*
G36*
G01D02*
G02X100429Y5906I0J3902D01*
G01Y9843D01*
G03X92520Y17752I-7909J0D01*
G01X5906D01*
G02X2004Y21654I0J3902D01*
G01Y521639D01*
X3998D01*
Y435031D01*
X3639Y434672D01*
Y409672D01*
X3998Y409313D01*
Y21718D01*
G03X5905Y19745I1907J-64D01*
G01X5906D01*
Y19746D01*
X91602D01*
Y19745D01*
X92520D01*
G02X102422Y9843I-1J-9903D01*
G01Y5906D01*
G03X104330Y3997I1908J-1D01*
G01X104331D01*
Y3998D01*
X397638D01*
G03X401514Y7874I0J3876D01*
G01Y1910871D01*
G02X401520Y1910949I1000J-38D01*
G01X401514D01*
Y1915529D01*
X401515D01*
Y1915541D01*
X401514Y1915551D01*
Y2078740D01*
G03X397638Y2082616I-3876J0D01*
G01X104331D01*
Y2082617D01*
X104330D01*
G03X102422Y2080709I0J-1908D01*
G01Y2076772D01*
G02X99522Y2069769I-9903J-1D01*
G02X92520Y2066868I-7003J7002D01*
G01X5971D01*
G03X4556Y2066310I-65J-1907D01*
G03X3998Y2064961I1350J-1348D01*
G01Y1608226D01*
X2004D01*
Y2064961D01*
G02X5905Y2068862I3901J0D01*
G01X92520D01*
G03X100429Y2076772I0J7909D01*
G01Y2080709D01*
G02X104331Y2084610I3902J-1D01*
G01X397638D01*
G02X403508Y2078740I0J-5870D01*
G01Y7874D01*
G02X397638Y2004I-5870J0D01*
G01X104331D01*
G37*
%LPC*%
G75*
G36*
G01X315169Y1871913D02*
G02X299003I-8083J9189D01*
G02X294834Y1881121I8084J9208D01*
G01Y1885021D01*
G02X299158Y1894363I12254J0D01*
G02X315014I7928J-9324D01*
G02X319338Y1885021I-7930J-9342D01*
G01Y1881121D01*
G02X315169Y1871913I-12253J0D01*
G37*
G36*
G01X65355Y1844272D02*
G02X44667Y1864960I0J20688D01*
G02X86043I20688J0D01*
G02X65355Y1844272I-20688J0D01*
G37*
G36*
G01X123238Y1809871D02*
G02X116602I-3318J-1643D01*
G03X115706Y1811314I-896J443D01*
G01X113105D01*
X112007Y1810216D01*
X108819D01*
G02Y1814020I0J1902D01*
G01X110431D01*
X111529Y1815118D01*
X115718D01*
G03X116612Y1816566I0J1000D01*
G02X123228I3308J1662D01*
G03X124122Y1815118I894J-448D01*
G01X135718D01*
G03X136612Y1816566I0J1000D01*
G02X143228I3308J1662D01*
G03X144122Y1815118I894J-448D01*
G01X166283D01*
X172644Y1821478D01*
G03X171937Y1823186I-707J708D01*
G01X159075D01*
G02Y1826988I0J1901D01*
G01X159353D01*
G03X160349Y1828083I0J1000D01*
G02X160399Y1828635I1495J143D01*
G03X159591Y1829896I-962J273D01*
G02X161267Y1830970I231J1484D01*
G03X162075Y1829709I962J-273D01*
G02X163339Y1828083I-231J-1484D01*
G03X164335Y1826988I996J-95D01*
G01X171395D01*
X184923Y1840516D01*
X230711D01*
G03X231064Y1840662I0J500D01*
G01X255585Y1865184D01*
X277905D01*
X278631Y1865910D01*
G02X281321Y1863220I1345J-1345D01*
G01X280203Y1862102D01*
G03Y1861394I353J-354D01*
G01X281585Y1860013D01*
G02X278895Y1857323I-1345J-1345D01*
G01X278252Y1857966D01*
X258576D01*
X233909Y1833300D01*
X190051D01*
G03X189698Y1833154I0J-500D01*
G01X167859Y1811314D01*
X144134D01*
G03X143238Y1809871I0J-1000D01*
G02X136602I-3318J-1643D01*
G03X135706Y1811314I-896J443D01*
G01X124134D01*
G03X123238Y1809871I0J-1000D01*
G37*
G36*
G01X108498Y1792378D02*
G02X106044Y1792524I-1278J-789D01*
G03X106113Y1793671I-782J623D01*
G02X108567Y1793525I1278J789D01*
G03X108498Y1792378I782J-623D01*
G37*
G36*
G01X123315Y1461672D02*
G02X116525I-3395J-1475D01*
G03X115607Y1463070I-917J398D01*
G01X114308D01*
X109103Y1461563D01*
G02X108045Y1465215I-529J1826D01*
G01X113768Y1466874D01*
X115832D01*
G03X116702Y1468368I1J1000D01*
G02X123138I3218J1829D01*
G03X124008Y1466874I869J-494D01*
G01X125158D01*
X135483Y1477198D01*
X135664D01*
G03X136569Y1478624I0J1000D01*
G02X143271I3351J1573D01*
G03X144176Y1477198I905J-426D01*
G01X151467D01*
X152832Y1475834D01*
X156329D01*
G03X157324Y1476934I0J1000D01*
G02X159216Y1479026I1892J190D01*
G01X163488D01*
X181015Y1496552D01*
X220124D01*
G03X220477Y1496698I0J500D01*
G01X246492Y1522714D01*
X297890D01*
X300922Y1525746D01*
G02X303612Y1523056I1345J-1345D01*
G01X299785Y1519230D01*
G03Y1518522I353J-354D01*
G01X303079Y1515228D01*
G02X300389Y1512538I-1345J-1345D01*
G01X297354Y1515573D01*
G03X297001Y1515720I-354J-353D01*
G01X249598D01*
G03X249245Y1515574I0J-500D01*
G01X222754Y1489082D01*
X184051D01*
X166999Y1472030D01*
X151256D01*
X150037Y1473249D01*
G03X149684Y1473396I-354J-353D01*
G01X144076D01*
G03X143192Y1471928I0J-1000D01*
G02X136218Y1470153I-3272J-1731D01*
G03X134511Y1470848I-1000J-12D01*
G01X126734Y1463070D01*
X124233D01*
G03X123315Y1461672I-1J-1000D01*
G37*
G36*
G01X353817Y721970D02*
G02X350515I-1651J-2265D01*
G03X350720Y722374I-295J404D01*
G01Y724256D01*
X350511Y724466D01*
G03X350156Y724613I-354J-353D01*
G01X349969Y724456D01*
X349923Y724203D01*
G02X344756Y723276I-2757J502D01*
G01X344755Y723277D01*
G03X344325Y723522I-430J-255D01*
G01X341346D01*
X341233Y723634D01*
G03X339643Y723394I-706J-708D01*
G02X336975Y727500I-2477J1311D01*
G03X337440Y727999I-35J499D01*
G01Y731411D01*
G03X336975Y731910I-500J0D01*
G02X335679Y737080I191J2795D01*
G03X335914Y737504I-265J424D01*
G01Y738522D01*
X348657Y751264D01*
X359082D01*
G03X359435Y751411I-1J500D01*
G01X361098Y753074D01*
X361133Y753198D01*
G02X362162Y754227I1444J-415D01*
G01X362286Y754262D01*
X390294Y782269D01*
G03X390440Y782622I-354J353D01*
G01Y950958D01*
G03X390294Y951311I-500J0D01*
G01X366603Y975001D01*
X317345D01*
G03X316638Y973294I0J-1000D01*
G01X337172Y952759D01*
Y942185D01*
G03X337318Y941832I500J0D01*
G01X343947Y935204D01*
X344071Y935169D01*
G02X345100Y934140I-415J-1444D01*
G01X345135Y934016D01*
X363416Y915734D01*
Y907504D01*
G03X363651Y907080I500J0D01*
G02X362667Y901948I-1486J-2375D01*
G01X362489Y901916D01*
X362257Y901638D01*
Y901456D01*
G03X362757Y900956I500J0D01*
G01X363174D01*
X366888Y897243D01*
Y892752D01*
X361990Y887854D01*
X339523D01*
X325382Y901996D01*
Y903851D01*
G03X324119Y904816I-1000J0D01*
G02Y910224I-734J2704D01*
G03X325382Y911189I263J965D01*
G01Y920575D01*
X317306Y928651D01*
Y940338D01*
X317243Y940451D01*
G02Y941905I1314J727D01*
G01X317306Y942018D01*
Y958258D01*
G03X317160Y958611I-500J0D01*
G01X251414Y1024356D01*
X189856D01*
X187114Y1027098D01*
X144192D01*
G03X143283Y1025681I0J-1000D01*
G02X143256Y1022528I-3363J-1548D01*
G03X144157Y1021094I901J-434D01*
G01X152661D01*
X156797Y1016958D01*
X163407D01*
G03X164269Y1018466I0J1000D01*
G02X168579I2155J1271D01*
G03X169441Y1016958I862J-508D01*
G01X170839D01*
G03X171192Y1017105I-1J500D01*
G01X172285Y1018198D01*
X175473D01*
G02Y1014394I0J-1902D01*
G01X173861D01*
X172622Y1013156D01*
X169819D01*
G03X168850Y1011911I1J-1000D01*
G02X168728Y1010323I-2426J-612D01*
G03X169649Y1008934I921J-389D01*
G01X173212D01*
X174353Y1010075D01*
G02X177043Y1007385I1345J-1345D01*
G01X174788Y1005130D01*
X169881D01*
G03X168894Y1003970I0J-1000D01*
G02X168744Y1002634I-2470J-399D01*
G03X169672Y1001260I927J-374D01*
G01X174539D01*
X176794Y999005D01*
G02X174104Y996315I-1345J-1345D01*
G01X172963Y997456D01*
X144008D01*
G03X143139Y995963I1J-1000D01*
G02X143105Y992247I-3219J-1829D01*
G03X143965Y990738I860J-509D01*
G01X163980D01*
G03X164756Y992368I0J1000D01*
G02X168642I1943J1576D01*
G03X169418Y990738I776J-630D01*
G01X171432D01*
X172554Y991860D01*
X175742D01*
G02Y988056I0J-1902D01*
G01X174130D01*
X173008Y986934D01*
X169156D01*
G03X168454Y985222I0J-1000D01*
G02X169019Y982502I-1755J-1783D01*
G03X169946Y981128I927J-374D01*
G01X170779D01*
X171834Y982182D01*
X175022D01*
G02Y978380I0J-1901D01*
G01X173617D01*
G03X173264Y978233I1J-500D01*
G01X172355Y977324D01*
X144081D01*
G03X143196Y975859I0J-1000D01*
G02X143279Y972578I-3276J-1724D01*
G03X144186Y971158I907J-420D01*
G01X163282D01*
G03X164258Y972376I0J1000D01*
G02X169140I2441J548D01*
G03X170116Y971158I976J-218D01*
G01X171113D01*
X173790Y973835D01*
G02X176480Y971145I1345J-1345D01*
G01X172689Y967354D01*
X144065D01*
G03X143183Y965882I-1J-1000D01*
G02X136657I-3263J-1748D01*
G03X135775Y967354I-881J472D01*
G01X124065D01*
G03X123183Y965882I-1J-1000D01*
G02X116657I-3263J-1748D01*
G03X115775Y967354I-881J472D01*
G01X115195D01*
X112411Y970138D01*
X105395D01*
G02X104193Y970567I1J1902D01*
G03X103613Y970604I-316J-388D01*
G02X100710Y972220I-1002J1616D01*
G01Y975434D01*
X106403Y981128D01*
X115668D01*
G03X116572Y982554I0J1000D01*
G02X116500Y985552I3348J1580D01*
G03X115576Y986934I-924J382D01*
G01X115330D01*
X110030Y992234D01*
X100626D01*
G03X99632Y991124I0J-1000D01*
G02X96646I-1493J-165D01*
G03X95652Y992234I-994J110D01*
G01X72768D01*
X58914Y1006089D01*
Y1015898D01*
G03X57206Y1016606I-1000J1D01*
G01X44598Y1003998D01*
Y997103D01*
X36135Y988640D01*
X30551D01*
X29226Y989964D01*
G03X27625Y989706I-707J-707D01*
G02X26544Y988610I-2235J1124D01*
G03X26118Y987262I462J-887D01*
G02X14103Y984333I-5650J-2929D01*
G02X14817Y987263I6365J1D01*
G03X14391Y988610I-888J460D01*
G02X17996Y991340I1156J2219D01*
G03X19178Y990566I979J205D01*
G02X21758Y990565I1288J-6233D01*
G03X22940Y991340I203J979D01*
G02X23002Y991580I2451J-505D01*
G03X22049Y992880I-954J300D01*
G01X21572D01*
X18050Y996403D01*
Y998736D01*
G03X17903Y999089I-500J-1D01*
G01X15604Y1001388D01*
X10112D01*
G03X9705Y1001180I-1J-500D01*
G02Y1004100I-2032J1460D01*
G03X10112Y1003892I406J292D01*
G01X12477D01*
G03X13354Y1005373I0J1000D01*
G02Y1007781I2193J1204D01*
G03X12477Y1009262I-877J481D01*
G01X10112D01*
G03X9705Y1009054I-1J-500D01*
G02Y1011974I-2032J1460D01*
G03X10112Y1011766I406J292D01*
G01X12477D01*
G03X13354Y1013247I0J1000D01*
G02X16425Y1016794I2193J1204D01*
G03X17776Y1017730I351J936D01*
G01Y1018326D01*
X16386Y1019716D01*
G03X15952Y1019856I-354J-353D01*
G02X13354Y1023529I-405J2469D01*
G03X12477Y1025010I-877J481D01*
G01X10112D01*
G03X9705Y1024802I-1J-500D01*
G02Y1027722I-2032J1460D01*
G03X10112Y1027514I406J292D01*
G01X16619D01*
X21698Y1022434D01*
Y1015358D01*
G03X21845Y1015005I500J1D01*
G01X22104Y1014745D01*
G03X22811I354J354D01*
G01X22915Y1014849D01*
X22946Y1014991D01*
G02X25794Y1016920I2443J-540D01*
G03X26228Y1017060I80J493D01*
G01X28181Y1019013D01*
G03X28328Y1019366I-353J354D01*
G01Y1019408D01*
G03X26774Y1020241I-1000J0D01*
G02X23930Y1024358I-1385J2084D01*
G03X24138Y1024764I-292J406D01*
G01Y1026033D01*
X43171Y1045066D01*
G03X42463Y1046774I-707J708D01*
G01X38542D01*
X28347Y1056968D01*
G03X26665Y1056036I-708J-707D01*
G02X24060Y1059853I-6194J-1430D01*
G03X24697Y1059912I283J412D01*
G03Y1060619I-354J353D01*
G01X24142Y1061174D01*
Y1063190D01*
G03X23934Y1063596I-500J0D01*
G02X26852I1459J2033D01*
G03X26644Y1063190I292J-406D01*
G01Y1062210D01*
X30308Y1058546D01*
G03X32015Y1059254I707J707D01*
G01Y1059374D01*
X31906Y1059589D01*
X31807Y1059660D01*
G02X34726Y1059659I1460J2032D01*
G03X34518Y1059253I292J-406D01*
G01Y1058273D01*
X42179Y1050612D01*
X67020D01*
G03X67728Y1052320I1J1000D01*
G01X41061Y1078986D01*
X36726D01*
G03X35738Y1077830I0J-1000D01*
G02X31006Y1078512I-2471J-390D01*
G01Y1078513D01*
G03X30908Y1079080I-452J214D01*
G01X29308Y1080680D01*
G03X27685Y1080374I-707J-707D01*
G02X23259Y1082683I-2292J1003D01*
G03X23186Y1083297I-427J261D01*
G01X18014Y1088470D01*
Y1089294D01*
G03X17867Y1089647I-500J-1D01*
G01X15578Y1091936D01*
X10116D01*
G03X9709Y1091728I-1J-500D01*
G02Y1094648I-2032J1460D01*
G03X10116Y1094440I406J292D01*
G01X12481D01*
G03X13358Y1095921I0J1000D01*
G02Y1098329I2193J1204D01*
G03X12481Y1099810I-877J481D01*
G01X10116D01*
G03X9709Y1099602I-1J-500D01*
G02Y1102522I-2032J1460D01*
G03X10116Y1102314I406J292D01*
G01X12481D01*
G03X13358Y1103795I0J1000D01*
G02X14071Y1107017I2193J1205D01*
G03X14187Y1108530I-591J806D01*
G01X8516Y1114201D01*
G03X8082Y1114341I-354J-353D01*
G02X10146Y1116405I-405J2469D01*
G03X10286Y1115971I493J-80D01*
G01X12020Y1114237D01*
G03X13533Y1114353I707J707D01*
G02X18020Y1112468I2018J-1480D01*
G03X18160Y1112034I493J-80D01*
G01X21544Y1108650D01*
Y1106141D01*
X22167Y1105518D01*
G03X22875I354J353D01*
G01X22963Y1105606D01*
X22999Y1105726D01*
G02X27426Y1106458I2394J-727D01*
G03X27832Y1106250I406J292D01*
G01X30197D01*
G03X31074Y1107732I0J1000D01*
G02X33672Y1111405I2193J1204D01*
G03X34106Y1111545I80J493D01*
G01X37985Y1115423D01*
G03X37277Y1117130I-707J707D01*
G01X36065D01*
X35777Y1116858D01*
X35765Y1116660D01*
G02X30914Y1115958I-2498J149D01*
G03X29267Y1116325I-940J-340D01*
G01X29068Y1116126D01*
X22873D01*
X19924Y1119076D01*
Y1124922D01*
X22784Y1127783D01*
G03X22924Y1128217I-353J354D01*
G02X24988Y1126153I2469J405D01*
G03X24554Y1126013I-80J-493D01*
G01X22573Y1124032D01*
G03X22426Y1123679I353J-354D01*
G01Y1123646D01*
G03X23988Y1122818I1000J0D01*
G02X27425Y1122208I1405J-2070D01*
G03X27832Y1122000I406J292D01*
G01X28404D01*
X29032Y1122628D01*
X29928D01*
G03X30882Y1123929I0J1000D01*
G02X35300Y1126144I2385J756D01*
G03X35706Y1125936I406J292D01*
G01X87371D01*
X89624Y1128188D01*
G03X88917Y1129896I-707J708D01*
G01X47785D01*
X37375Y1140305D01*
G03X35697Y1139836I-707J-707D01*
G02X31023Y1141540I-2430J597D01*
G01X31094Y1141684D01*
X31042Y1142001D01*
X29327Y1143716D01*
G03X27698Y1143398I-708J-707D01*
G02X22965Y1144973I-2305J972D01*
G03X21994Y1146214I-970J241D01*
G01X18950D01*
G03X17979Y1144973I-1J-1000D01*
G02X14071Y1146387I-2428J-603D01*
G03X14186Y1147901I-592J806D01*
G01X8516Y1153571D01*
G03X8082Y1153711I-354J-353D01*
G02X10146Y1155775I-405J2469D01*
G03X10286Y1155341I493J-80D01*
G01X12020Y1153607D01*
G03X13533Y1153723I707J707D01*
G02X14071Y1154262I2019J-1478D01*
G03X14187Y1155775I-591J806D01*
G01X8516Y1161446D01*
G03X8082Y1161586I-354J-353D01*
G02X10146Y1163650I-405J2469D01*
G03X10286Y1163216I493J-80D01*
G01X12020Y1161482D01*
G03X13533Y1161598I707J707D01*
G02X13718Y1161821I2015J-1483D01*
G03X13692Y1163209I-733J681D01*
G01X10560Y1166342D01*
Y1167041D01*
G03X10413Y1167394I-500J-1D01*
G01X9368Y1168439D01*
Y1168468D01*
X8516Y1169320D01*
G03X8082Y1169460I-354J-353D01*
G02X10146Y1171524I-405J2469D01*
G03X10286Y1171090I493J-80D01*
G01X11872Y1169504D01*
Y1169475D01*
X13062Y1168284D01*
Y1167585D01*
G03X13209Y1167232I500J1D01*
G01X16003Y1164438D01*
X20632D01*
G03X21340Y1166145I1J1000D01*
G01X14300Y1173185D01*
Y1173427D01*
G03X14092Y1173833I-500J0D01*
G02X17446Y1174233I1458J2033D01*
G03X17471Y1173553I379J-327D01*
G01X21782Y1169242D01*
G03X23318Y1169390I707J707D01*
G02X27425Y1169452I2075J-1398D01*
G03X27832Y1169244I406J292D01*
G01X33707D01*
X37726Y1173263D01*
X37727Y1175332D01*
G03X36019Y1176040I-1000J1D01*
G01X34594Y1174614D01*
X27832D01*
G03X27425Y1174406I-1J-500D01*
G02Y1177326I-2032J1460D01*
G03X27832Y1177118I406J292D01*
G01X30197D01*
G03X31074Y1178599I0J1000D01*
G02Y1181007I2193J1204D01*
G03X30197Y1182488I-877J481D01*
G01X27832D01*
G03X27425Y1182280I-1J-500D01*
G02Y1185200I-2032J1460D01*
G03X27832Y1184992I406J292D01*
G01X30197D01*
G03X31074Y1186473I0J1000D01*
G02X33672Y1190146I2193J1204D01*
G03X34106Y1190286I80J493D01*
G01X38032Y1194212D01*
Y1194730D01*
X84922Y1241620D01*
Y1242985D01*
G03X84069Y1243338I-500J-1D01*
G01X53717Y1212986D01*
X32238D01*
X29156Y1209904D01*
X28537D01*
G03X27639Y1208464I0J-1000D01*
G02X23147I-2246J-1102D01*
G03X22249Y1209904I-898J440D01*
G01X19113D01*
X16390Y1212627D01*
G03X15956Y1212767I-354J-353D01*
G02X13533Y1213756I-406J2469D01*
G03X12020Y1213872I-806J-591D01*
G01X10286Y1212138D01*
G03X10146Y1211704I353J-354D01*
G02X8082Y1213768I-2469J-405D01*
G03X8516Y1213908I80J493D01*
G01X11517Y1216908D01*
G03X10809Y1218616I-707J708D01*
G01X10487D01*
G03X10019Y1218292I0J-500D01*
G02X9250Y1221118I-2342J880D01*
G01X12192D01*
G03X13151Y1222402I0J1000D01*
G02X15956Y1225579I2400J708D01*
G03X16390Y1225719I80J493D01*
G01X19639Y1228968D01*
X28540D01*
X29487Y1228020D01*
G03X31072Y1228248I707J707D01*
G02X31158Y1228393I2194J-1203D01*
G01X31236Y1228516D01*
Y1228662D01*
G03X30736Y1229162I-500J0D01*
G01X30622D01*
X26890Y1232894D01*
X19437D01*
G03X19084Y1232747I1J-500D01*
G01X18160Y1231823D01*
G03X18020Y1231390I354J-353D01*
G01Y1231389D01*
G02X15956Y1233453I-2469J-405D01*
G03X16390Y1233593I80J493D01*
G01X16530Y1233733D01*
G03X16177Y1234586I-354J353D01*
G01X10560D01*
G03X10080Y1234226I0J-500D01*
G01Y1234225D01*
G02X8823Y1237145I-2403J696D01*
G01X8931Y1237090D01*
X12134D01*
G03X13110Y1238309I0J1000D01*
G02X17992I2441J549D01*
G03X18968Y1237090I976J-219D01*
G01X21976D01*
G03X22952Y1238309I0J1000D01*
G02X27426Y1240318I2441J550D01*
G03X27832Y1240110I406J292D01*
G01X30197D01*
G03X31074Y1241591I0J1000D01*
G02Y1243999I2193J1204D01*
G03X30197Y1245480I-877J481D01*
G01X27832D01*
G03X27425Y1245272I-1J-500D01*
G02Y1248192I-2032J1460D01*
G03X27832Y1247984I406J292D01*
G01X35425D01*
X54896Y1267454D01*
G03X55042Y1267807I-354J353D01*
G01Y1300589D01*
G03X53334Y1301297I-1000J1D01*
G01X44762Y1292724D01*
X36337D01*
G03X35460Y1291243I0J-1000D01*
G02X31235Y1288580I-2193J-1203D01*
G03X30828Y1288788I-406J-292D01*
G01X24456D01*
X22585Y1290659D01*
G03X21878I-353J-354D01*
G01X18160Y1286941D01*
G03X18020Y1286507I353J-354D01*
G02X15956Y1288571I-2469J-405D01*
G03X16390Y1288711I80J493D01*
G01X19908Y1292229D01*
Y1293533D01*
G03X19055Y1293886I-500J-1D01*
G01X17893Y1292724D01*
X17718D01*
G02X13533Y1292496I-2167J1252D01*
G03X12020Y1292612I-806J-591D01*
G01X10286Y1290878D01*
G03X10146Y1290444I353J-354D01*
G02X8082Y1292508I-2469J-405D01*
G03X8516Y1292648I80J493D01*
G01X10823Y1294954D01*
G03X10115Y1296662I-707J708D01*
G01X9994D01*
X9780Y1296552D01*
X9709Y1296453D01*
G02X9710Y1299372I-2032J1460D01*
G03X10116Y1299164I406J292D01*
G01X12348D01*
G03X12703Y1299311I1J500D01*
G01X12863Y1299472D01*
X13209D01*
G03X13599Y1300284I0J500D01*
G02X13082Y1302255I1952J1565D01*
G03X12942Y1302689I-493J80D01*
G01X11006Y1304626D01*
Y1304781D01*
G03X10506Y1305281I-500J0D01*
G01X10505D01*
G03X10034Y1304950I0J-500D01*
G01Y1304949D01*
G02X6218Y1307820I-2357J838D01*
G03X6426Y1308226I-292J406D01*
G01Y1309762D01*
X9258Y1312594D01*
Y1318081D01*
G03X8092Y1319068I-1000J1D01*
G02X10124Y1322055I-415J2467D01*
G03X11809Y1321556I978J208D01*
G01X13667Y1323414D01*
X13690Y1323789D01*
X13574Y1323939D01*
G02X16551Y1327766I1977J1533D01*
G03X17950Y1328682I399J916D01*
G01Y1330136D01*
G03X16551Y1331052I-1000J0D01*
G02X17898Y1334213I-1000J2294D01*
G03X19543Y1333853I938J347D01*
G01X20272Y1334582D01*
G03X19688Y1336282I-707J707D01*
G02X14107Y1342598I783J6316D01*
G02X14821Y1345528I6365J1D01*
G03X14395Y1346875I-888J460D01*
G02X18000Y1349605I1156J2219D01*
G03X19182Y1348831I979J205D01*
G02X21762Y1348830I1288J-6233D01*
G03X22944Y1349605I203J979D01*
G02X26548Y1346875I2449J-511D01*
G03X26122Y1345527I462J-887D01*
G02X26010Y1339462I-5651J-2929D01*
G03X26880Y1337970I870J-492D01*
G01X27385D01*
X30592Y1341176D01*
G03X30738Y1341529I-354J353D01*
G01Y1346072D01*
X33517Y1348852D01*
G03X32940Y1350550I-707J707D01*
G02X33688Y1355497I328J2480D01*
G03X34856Y1356483I168J986D01*
G01Y1365327D01*
G03X33688Y1366313I-1000J0D01*
G02Y1371245I-421J2466D01*
G03X34856Y1372231I168J986D01*
G01Y1373201D01*
G03X33688Y1374187I-1000J0D01*
G02Y1379119I-421J2466D01*
G03X34856Y1380105I168J986D01*
G01Y1487255D01*
X25392Y1496720D01*
Y1548119D01*
X30778Y1553505D01*
Y1591077D01*
X48177Y1608477D01*
G03X47842Y1610112I-707J707D01*
G02X51875Y1614145I1153J2880D01*
G03X53510Y1613810I928J372D01*
G01X57240Y1617539D01*
G03X57386Y1617892I-354J353D01*
G01Y1619659D01*
G03X55803Y1620471I-1000J-1D01*
G02Y1625513I-1808J2521D01*
G03X57386Y1626325I583J813D01*
G01Y1818857D01*
G03X57240Y1819210I-500J0D01*
G01X25152Y1851297D01*
Y1937558D01*
X21484Y1941227D01*
Y1944047D01*
G03X19837Y1944810I-1000J0D01*
G02X16217Y1950167I-2102J2481D01*
G03X16484Y1950609I-233J442D01*
G01Y1960066D01*
X20899Y1964482D01*
X25275D01*
X29040Y1960717D01*
Y1960579D01*
G03X30673Y1959806I1000J1D01*
G02X33695Y1960398I2062J-2515D01*
G03X34196Y1960522I148J478D01*
G01X36487Y1962812D01*
X54540D01*
X57954Y1959399D01*
Y1950058D01*
X36040Y1928145D01*
G03X35894Y1927792I354J-353D01*
G01Y1855128D01*
X66156Y1824866D01*
G03X67864Y1825574I708J707D01*
G01Y1836251D01*
X88012Y1856400D01*
Y1956128D01*
X27024Y2017116D01*
Y2040602D01*
X19098Y2048528D01*
X18828Y2048595D01*
X18695Y2048554D01*
G02X19837Y2054142I-960J3107D01*
G03X21484Y2054905I647J763D01*
G01Y2058343D01*
G03X21217Y2058785I-500J0D01*
G02X24253I1518J2876D01*
G03X23986Y2058343I233J-442D01*
G01Y2054905D01*
G03X25633Y2054142I1000J0D01*
G02X27567Y2054909I2103J-2481D01*
G01X27759Y2054919D01*
X27894Y2055054D01*
G03Y2055762I-353J354D01*
G01X27614Y2056042D01*
Y2063669D01*
X30743Y2066798D01*
X39368D01*
X41372Y2064794D01*
X41642Y2064727D01*
X41775Y2064768D01*
G02X39628Y2062621I960J-3107D01*
G01X39669Y2062754D01*
X39602Y2063024D01*
X38332Y2064294D01*
X36661D01*
G03X35737Y2062910I-1J-1000D01*
G02X34253Y2058785I-3002J-1249D01*
G03X33986Y2058343I233J-442D01*
G01Y2056177D01*
G03X34133Y2055824I500J1D01*
G01X34922Y2055035D01*
Y2043032D01*
G03X36629Y2042324I1000J-1D01*
G01X44504Y2050200D01*
G03X44628Y2050701I-354J353D01*
G02X49837Y2054142I3107J960D01*
G03X51484Y2054905I647J763D01*
G01Y2058343D01*
G03X51217Y2058785I-500J0D01*
G02X54253I1518J2876D01*
G03X53986Y2058343I233J-442D01*
G01Y2050040D01*
X37522Y2033575D01*
Y2021466D01*
X98510Y1960478D01*
Y1852050D01*
X78506Y1832047D01*
G03X78360Y1831694I354J-353D01*
G01Y1621668D01*
G03X78506Y1621315I500J0D01*
G01X83340Y1616482D01*
Y1571122D01*
X45394Y1533177D01*
G03X45248Y1532824I354J-353D01*
G01Y1525221D01*
G03X47129Y1524748I1000J0D01*
G02X86043Y1514960I18226J-9788D01*
G02X65355Y1494272I-20688J0D01*
G02X57876Y1495672I2J20687D01*
G03X56808Y1494032I-361J-933D01*
G01X57964Y1492875D01*
Y1459358D01*
G03X59672Y1458650I1000J-1D01*
G01X100814Y1499792D01*
Y1729670D01*
X126540Y1755396D01*
X135589D01*
G03X136510Y1756786I0J1000D01*
G02X143330I3410J1442D01*
G03X144251Y1755396I921J-390D01*
G01X311460D01*
G03X311813Y1755542I0J500D01*
G01X323674Y1767404D01*
G03X323077Y1769105I-707J707D01*
G02X326170Y1772198I308J2785D01*
G03X327871Y1771601I994J110D01*
G01X336663Y1780393D01*
G03X336274Y1782048I-707J707D01*
G02X339822Y1785596I891J2657D01*
G03X341477Y1785207I948J318D01*
G01X342227Y1785956D01*
X344366D01*
G03X344790Y1786191I0J500D01*
G02X347667Y1781948I2375J-1486D01*
G01X347489Y1781916D01*
X347257Y1781638D01*
Y1781456D01*
G03X347757Y1780956I500J0D01*
G01X349366D01*
G03X349790Y1781191I0J500D01*
G02Y1778219I2375J-1486D01*
G03X349366Y1778454I-424J-265D01*
G01X348040D01*
X347797Y1778211D01*
G03Y1777503I353J-354D01*
G01X347884Y1777416D01*
X348001Y1777379D01*
G02X348651Y1772330I-836J-2674D01*
G03X348416Y1771906I265J-424D01*
G01Y1770297D01*
G03X348916Y1769797I500J0D01*
G01X349098D01*
X349376Y1770029D01*
X349408Y1770207D01*
G02X351536Y1766974I2757J-502D01*
G01X351410Y1767003D01*
X351161Y1766932D01*
X337209Y1752979D01*
X337174Y1752855D01*
G02X336145Y1751826I-1444J415D01*
G01X336021Y1751791D01*
X332490Y1748261D01*
G03X333198Y1746553I707J-708D01*
G01X347680D01*
X375424Y1774297D01*
G03X374542Y1775989I-707J707D01*
G02X378871Y1786247I-1157J6531D01*
G03X380698Y1786809I827J562D01*
G01Y1896530D01*
X358027Y1919201D01*
X357903Y1919236D01*
G02X356875Y1920261I415J1444D01*
G01X330538Y1946599D01*
Y1961727D01*
X335512Y1966702D01*
X357363D01*
X363482Y1960583D01*
Y1957462D01*
G03X363707Y1957044I500J0D01*
G02X360623I-1542J-2339D01*
G03X360848Y1957462I-275J418D01*
G01Y1959493D01*
X360728Y1959613D01*
X360232D01*
X359954Y1959381D01*
X359922Y1959203D01*
G02X354434Y1960334I-2757J502D01*
G01X354463Y1960460D01*
X354392Y1960709D01*
X352878Y1962222D01*
X350651D01*
G03X349734Y1960823I0J-1000D01*
G02X344596I-2569J-1118D01*
G03X343679Y1962222I-917J399D01*
G01X340651D01*
G03X339734Y1960823I0J-1000D01*
G02X336094Y1957116I-2569J-1118D01*
G03X334712Y1956192I-382J-924D01*
G01Y1953218D01*
G03X336094Y1952294I1000J0D01*
G02X339540Y1951191I1071J-2589D01*
G03X339964Y1950956I424J265D01*
G01X341573D01*
G03X342073Y1951456I0J500D01*
G01Y1951638D01*
X341841Y1951916D01*
X341663Y1951948D01*
G02X343193Y1952098I502J2757D01*
G03X342852Y1950461I366J-930D01*
G01X342921Y1950392D01*
G03X344558Y1950733I707J707D01*
G02X348193Y1947098I2607J-1028D01*
G03X347852Y1945461I366J-930D01*
G01X347921Y1945392D01*
G03X349558Y1945733I707J707D01*
G02X354922Y1945207I2607J-1028D01*
G01X354954Y1945029D01*
X355232Y1944797D01*
X355414D01*
G03X355914Y1945297I0J500D01*
G01Y1946906D01*
G03X355679Y1947330I-500J0D01*
G02X358651I1486J2375D01*
G03X358416Y1946906I265J-424D01*
G01Y1945297D01*
G03X358916Y1944797I500J0D01*
G01X359098D01*
X359376Y1945029D01*
X359408Y1945207D01*
G02X363651Y1942330I2757J-502D01*
G03X363416Y1941906I265J-424D01*
G01Y1935224D01*
G03X363562Y1934871I500J0D01*
G01X379694Y1918740D01*
X379818Y1918705D01*
G02X380847Y1917676I-415J-1444D01*
G01X380882Y1917552D01*
X390160Y1908274D01*
Y1774444D01*
X350840Y1735124D01*
X297497D01*
X293038Y1739584D01*
G03X292685Y1739730I-353J-354D01*
G01X170153D01*
G03X169653Y1739230I0J-500D01*
G01Y1739224D01*
G02X166649I-1502J-16D01*
G01Y1739230D01*
G03X166149Y1739730I-500J0D01*
G01X165499D01*
G03X164603Y1738286I0J-1000D01*
G02X161911I-1346J-667D01*
G03X161015Y1739730I-896J444D01*
G01X147377D01*
G03X146378Y1738782I0J-1000D01*
G02X143378I-1500J79D01*
G03X142379Y1739730I-999J-52D01*
G01X134996D01*
X120648Y1725382D01*
G03X121050Y1723722I707J-707D01*
G02X118031Y1717013I-1130J-3525D01*
G03X116520Y1716153I-511J-860D01*
G01Y1714241D01*
G03X118031Y1713381I1000J0D01*
G02Y1707013I1889J-3184D01*
G03X116520Y1706153I-511J-860D01*
G01Y1704241D01*
G03X118031Y1703381I1000J0D01*
G02Y1697013I1889J-3184D01*
G03X116520Y1696153I-511J-860D01*
G01Y1694241D01*
G03X118031Y1693381I1000J0D01*
G02Y1687013I1889J-3184D01*
G03X116520Y1686153I-511J-860D01*
G01Y1684241D01*
G03X118031Y1683381I1000J0D01*
G02Y1677013I1889J-3184D01*
G03X116520Y1676153I-511J-860D01*
G01Y1674241D01*
G03X118031Y1673381I1000J0D01*
G02Y1667013I1889J-3184D01*
G03X116520Y1666153I-511J-860D01*
G01Y1664241D01*
G03X118031Y1663381I1000J0D01*
G02Y1657013I1889J-3184D01*
G03X116520Y1656153I-511J-860D01*
G01Y1654241D01*
G03X118031Y1653381I1000J0D01*
G02Y1647013I1889J-3184D01*
G03X116520Y1646153I-511J-860D01*
G01Y1644241D01*
G03X118031Y1643381I1000J0D01*
G02Y1637013I1889J-3184D01*
G03X116520Y1636153I-511J-860D01*
G01Y1634241D01*
G03X118031Y1633381I1000J0D01*
G02Y1627013I1889J-3184D01*
G03X116520Y1626153I-511J-860D01*
G01Y1624241D01*
G03X118031Y1623381I1000J0D01*
G02Y1617013I1889J-3184D01*
G03X116520Y1616153I-511J-860D01*
G01Y1614241D01*
G03X118031Y1613381I1000J0D01*
G02Y1607013I1889J-3184D01*
G03X116520Y1606153I-511J-860D01*
G01Y1486860D01*
X87684Y1458024D01*
Y1390741D01*
G03X89392Y1390033I1000J-1D01*
G01X95031Y1395673D01*
X95066Y1395797D01*
G02X96095Y1396826I1444J-415D01*
G01X96219Y1396861D01*
X106681Y1407322D01*
X115608D01*
G03X116525Y1408721I0J1000D01*
G02X123315I3395J1476D01*
G03X124232Y1407322I917J-399D01*
G01X135608D01*
G03X136525Y1408721I0J1000D01*
G02X143315I3395J1476D01*
G03X144232Y1407322I917J-399D01*
G01X149048D01*
G03X149401Y1407468I0J500D01*
G01X155604Y1413672D01*
X322169D01*
X331520Y1423023D01*
Y1426079D01*
X336084Y1430643D01*
G03X335847Y1432232I-707J707D01*
G02X337794Y1437436I1317J2473D01*
G01X337920Y1437407D01*
X338169Y1437478D01*
X341183Y1440492D01*
X358585D01*
X365302Y1433776D01*
G03X366976Y1434226I707J707D01*
G02X368672Y1427853I6409J-1707D01*
G03X366962Y1427150I-710J-704D01*
G01Y1417709D01*
X352159Y1402906D01*
X352122Y1402790D01*
G02X351143Y1401811I-1432J453D01*
G01X351027Y1401774D01*
X346643Y1397391D01*
G03X347351Y1395684I707J-707D01*
G01X372233D01*
X388680Y1412130D01*
G03X388826Y1412483I-354J353D01*
G01Y1524680D01*
G03X388680Y1525033I-500J0D01*
G01X343111Y1570601D01*
X342987Y1570636D01*
G02X341958Y1571665I415J1444D01*
G01X341923Y1571789D01*
X329072Y1584640D01*
Y1612352D01*
X334314Y1617594D01*
X355793D01*
X363416Y1609970D01*
Y1607504D01*
G03X363651Y1607080I500J0D01*
G02X360679I-1486J-2375D01*
G03X360914Y1607504I-265J424D01*
G01Y1608727D01*
G03X360767Y1609080I-500J-1D01*
G01X360694Y1609154D01*
G03X359987Y1609153I-353J-354D01*
G01X359895Y1609061D01*
X359860Y1608937D01*
G02X354434Y1610334I-2695J768D01*
G01X354463Y1610460D01*
X354392Y1610709D01*
X352383Y1612718D01*
X350391D01*
G03X349542Y1611188I-1J-1000D01*
G02X344788I-2377J-1483D01*
G03X343939Y1612718I-848J530D01*
G01X340391D01*
G03X339542Y1611188I-1J-1000D01*
G02X335531Y1607428I-2377J-1484D01*
G03X333948Y1606616I-583J-812D01*
G01Y1602794D01*
G03X335531Y1601982I1000J0D01*
G02X338651Y1597330I1634J-2277D01*
G03X338416Y1596906I265J-424D01*
G01Y1595297D01*
G03X338916Y1594797I500J0D01*
G01X339098D01*
X339376Y1595029D01*
X339408Y1595207D01*
G02X343651Y1592330I2757J-502D01*
G03X343416Y1591906I265J-424D01*
G01Y1584707D01*
X354206Y1573917D01*
G03X355914Y1574625I708J707D01*
G01Y1592078D01*
G03X354191Y1592769I-1000J0D01*
G02X354922Y1595207I-2026J1936D01*
G01X354954Y1595029D01*
X355232Y1594797D01*
X355414D01*
G03X355914Y1595297I0J500D01*
G01Y1596906D01*
G03X355679Y1597330I-500J0D01*
G02X358651I1486J2375D01*
G03X358416Y1596906I265J-424D01*
G01Y1595297D01*
G03X358916Y1594797I500J0D01*
G01X359098D01*
X359376Y1595029D01*
X359408Y1595207D01*
G02X363651Y1592330I2757J-502D01*
G03X363416Y1591906I265J-424D01*
G01Y1572497D01*
G03X363562Y1572144I500J0D01*
G01X368120Y1567587D01*
X368244Y1567552D01*
G02X369273Y1566523I-415J-1444D01*
G01X369308Y1566399D01*
X398786Y1536921D01*
Y1408148D01*
X376361Y1385724D01*
X300747D01*
X296393Y1381370D01*
X260060D01*
X255706Y1385724D01*
X237768D01*
G03X237060Y1384016I-1J-1000D01*
G01X287097Y1333980D01*
G03X288714Y1335103I708J707D01*
G02X298687Y1325130I18373J8400D01*
G03X297564Y1323513I-416J-909D01*
G01X321234Y1299842D01*
Y1284575D01*
G03X322132Y1283580I1000J0D01*
G02Y1280592I-154J-1494D01*
G03X321234Y1279597I102J-995D01*
G01Y1275302D01*
X332624Y1263912D01*
G03X333332I354J353D01*
G01X336002Y1266582D01*
X352058D01*
X356161Y1262478D01*
X356410Y1262407D01*
X356536Y1262436D01*
G02X357802Y1256976I629J-2731D01*
G01X357663Y1256944D01*
X357562Y1256843D01*
G03Y1256135I353J-354D01*
G01X357741Y1255956D01*
X359366D01*
G03X359790Y1256191I0J500D01*
G02X362667Y1251948I2375J-1486D01*
G01X362489Y1251916D01*
X362257Y1251638D01*
Y1251456D01*
G03X362757Y1250956I500J0D01*
G01X363539D01*
X388068Y1226428D01*
Y1180681D01*
X388130Y1180568D01*
G02Y1179114I-1314J-727D01*
G01X388068Y1179001D01*
Y1149427D01*
X397822Y1139672D01*
Y1076532D01*
X370745Y1049454D01*
X348004D01*
G03X347035Y1048210I0J-1000D01*
G02X344121I-1457J-366D01*
G03X343152Y1049454I-969J244D01*
G01X338138D01*
G03X337155Y1048634I0J-1000D01*
G02X334199I-1478J270D01*
G03X333216Y1049454I-983J-180D01*
G01X328723D01*
X327657Y1048388D01*
X318761D01*
X317695Y1049454D01*
X257632D01*
G03X256924Y1047747I-1J-1000D01*
G01X303185Y1001487D01*
G03X304858Y1001935I707J707D01*
G02X307923Y998870I2416J-649D01*
G03X307475Y997197I259J-966D01*
G01X318100Y986572D01*
X370648D01*
X400974Y956246D01*
Y773905D01*
X392775Y765706D01*
X392744Y765565D01*
G02X391607Y764428I-1466J329D01*
G01X391466Y764397D01*
X366632Y739564D01*
X357825D01*
G03X357471Y739417I0J-500D01*
G01X357197Y739142D01*
G03X357710Y737454I707J-707D01*
G02X354409Y734203I-544J-2749D01*
G01X354377Y734381D01*
X354099Y734613D01*
X353918D01*
G03X353418Y734113I0J-500D01*
G01Y732504D01*
G03X353653Y732080I500J0D01*
G02X353436Y727207I-1487J-2375D01*
G03X352901Y726164I453J-891D01*
G01X353612Y725454D01*
Y725297D01*
G03X354112Y724797I500J0D01*
G01X354375Y725016D01*
X354409Y725207D01*
G02Y724203I2757J-502D01*
G01X354377Y724381D01*
X354099Y724613D01*
X353904D01*
X353612Y724321D01*
Y722374D01*
G03X353817Y721970I500J0D01*
G37*
G36*
G01X113018Y419566D02*
G02X109016I-2001J0D01*
G01Y425519D01*
X116832Y433336D01*
G03X116888Y433977I-353J354D01*
G02X123299Y434589I3032J2125D01*
G03X124211Y433180I913J-409D01*
G01X135629D01*
G03X136541Y434589I-1J1000D01*
G02X143299I3379J1513D01*
G03X144211Y433180I913J-409D01*
G01X148968D01*
X151336Y430812D01*
X156037D01*
G03X156960Y432198I0J1000D01*
G02X158807Y434970I1847J771D01*
G01X159019D01*
G03X160018Y436030I0J1000D01*
G02X163016I1499J89D01*
G03X164015Y434970I999J-60D01*
G01X218956D01*
X256302Y472316D01*
X261543D01*
X264322Y475095D01*
G02X267152Y472265I1415J-1415D01*
G01X263625Y468738D01*
G03X263624Y468030I353J-354D01*
G01X267137Y464517D01*
G02X264307Y461687I-1415J-1415D01*
G01X261746Y464248D01*
X259775D01*
X222337Y426810D01*
X149678D01*
X147310Y429178D01*
X144139D01*
G03X143242Y427736I0J-1000D01*
G02X136598I-3322J-1634D01*
G03X135701Y429178I-897J442D01*
G01X124139D01*
G03X123242Y427736I0J-1000D01*
G02X116357Y425095I-3323J-1633D01*
G03X114688Y425531I-962J-272D01*
G01X113018Y423861D01*
Y419566D01*
G37*
G36*
G01X116668Y397872D02*
G02X116602Y394460I3252J-1770D01*
G03X115223Y394892I-896J-444D01*
G02X115274Y397493I-725J1315D01*
G03X116668Y397872I516J857D01*
G37*
G36*
G01X65354Y94272D02*
G02X44666Y114960I0J20688D01*
G02X65351Y135647I20687J0D01*
G01X65357D01*
G02X86042Y114960I-2J-20687D01*
G02X65354Y94272I-20688J0D01*
G37*
G36*
G01X123160Y69862D02*
G02X116680I-3240J-1791D01*
G03X115805Y71346I-875J484D01*
G01X115343D01*
G03X114990Y71199I1J-500D01*
G01X114133Y70342D01*
X107263D01*
G02Y74146I0J1902D01*
G01X112557D01*
X113560Y75148D01*
X115629D01*
G03X116542Y76557I0J1000D01*
G02X123298I3378J1514D01*
G03X124211Y75148I913J-409D01*
G01X127048D01*
X136670Y84770D01*
X136787D01*
G03X137287Y85270I0J500D01*
G01Y85461D01*
X137160Y85604D01*
G02X143149Y86260I2760J2467D01*
G03X144021Y84770I872J-490D01*
G01X155733D01*
X156168Y84335D01*
G03X156876I354J353D01*
G01X156958Y84417D01*
X157033Y84640D01*
X157017Y84757D01*
G02X158901Y86918I1884J259D01*
G01X159459D01*
G03X159959Y87418I0J500D01*
G01Y87507D01*
X159929Y87591D01*
G02X159900Y88538I1410J517D01*
G03X159132Y89806I-958J286D01*
G02X160856Y90851I285J1475D01*
G03X161624Y89583I958J-286D01*
G02X162837Y87994I-285J-1475D01*
G03X163834Y86918I997J-76D01*
G01X197610D01*
G03X197963Y87064I0J500D01*
G01X235662Y124764D01*
X250745D01*
X255602Y129621D01*
G02X258292Y126931I1345J-1345D01*
G01X253721Y122360D01*
G03Y121652I353J-354D01*
G01X258470Y116904D01*
G02X255780Y114214I-1345J-1345D01*
G01X252437Y117558D01*
G03X252084Y117704I-353J-354D01*
G01X238795D01*
G03X238442Y117558I0J-500D01*
G01X200743Y79858D01*
X155266D01*
X154303Y80821D01*
G03X153950Y80968I-354J-353D01*
G01X144223D01*
G03X143308Y79564I0J-1000D01*
G02X136373Y77010I-3388J-1493D01*
G03X134708Y77430I-958J-287D01*
G01X128624Y71346D01*
X124035D01*
G03X123160Y69862I0J-1000D01*
G37*
G36*
G01X344749Y18622D02*
G02X341851Y22489I-2584J1083D01*
G01X342041Y22510D01*
X342294Y22794D01*
Y26616D01*
X342041Y26900D01*
X341851Y26921D01*
G02X340679Y32080I314J2784D01*
G03X340914Y32504I-265J424D01*
G01Y34113D01*
G03X340414Y34613I-500J0D01*
G01X340232D01*
X339954Y34381D01*
X339922Y34203D01*
G02X337794Y37436I-2757J502D01*
G01X337920Y37407D01*
X338169Y37478D01*
X345743Y45052D01*
X350818D01*
G03X351171Y45198I0J500D01*
G01X358452Y52480D01*
X358487Y52604D01*
G02X359516Y53633I1444J-415D01*
G01X359640Y53668D01*
X366072Y60100D01*
G03X365071Y61763I-707J707D01*
G02X376859Y73551I-5229J17017D01*
G03X378522Y72550I956J-294D01*
G01X390838Y84865D01*
G03X390984Y85218I-354J353D01*
G01Y201571D01*
X367535Y225020D01*
X346035D01*
G03X345327Y223312I-1J-1000D01*
G01X356161Y212478D01*
X356410Y212407D01*
X356536Y212436D01*
G02X357693Y206953I629J-2731D01*
G01X357542Y206924D01*
X357433Y206815D01*
G03Y206108I354J-354D01*
G01X357438Y206103D01*
G03X357792Y205956I354J353D01*
G01X359366D01*
G03X359790Y206191I0J500D01*
G02X364101Y202679I2375J-1486D01*
G03X364792Y200956I691J-723D01*
G01X365583D01*
X368260Y198280D01*
Y192150D01*
X364322Y188212D01*
X337981D01*
X328490Y197703D01*
Y216091D01*
X320081Y224500D01*
X319957Y224535D01*
G02X319645Y224665I418J1443D01*
G01X319532Y224728D01*
X317370D01*
X209556Y332541D01*
G03X207849Y331823I-707J-707D01*
G02X204634Y335038I-3252J-37D01*
G03X205352Y336745I11J1000D01*
G01X200391Y341706D01*
X97021D01*
X73056Y365672D01*
Y436245D01*
X96130Y459319D01*
Y516387D01*
G03X94422Y517095I-1000J1D01*
G01X75358Y498030D01*
X69226D01*
X57250Y486054D01*
G03X58298Y484407I707J-707D01*
G02X86043Y464960I7057J-19447D01*
G02X65355Y444272I-20688J0D01*
G02X56864Y446095I0J20688D01*
G03X55747Y444476I-410J-912D01*
G01X66800Y433422D01*
Y414624D01*
X49810Y397634D01*
Y396895D01*
G03X51563Y396236I1000J0D01*
G02Y385432I6172J-5402D01*
G03X49810Y384773I-753J-659D01*
G01Y313193D01*
X77474Y285529D01*
Y222992D01*
X51671Y197188D01*
X25753D01*
X19098Y203843D01*
X18828Y203910D01*
X18695Y203869D01*
G02X19837Y209457I-960J3107D01*
G03X21484Y210220I647J763D01*
G01Y213658D01*
G03X21217Y214100I-500J0D01*
G02X24253I1518J2876D01*
G03X23986Y213658I233J-442D01*
G01Y210220D01*
G03X25633Y209457I1000J0D01*
G02X30842Y206016I2102J-2481D01*
G01X30801Y205883D01*
X30868Y205613D01*
X33989Y202492D01*
X41387D01*
G03X42095Y204199I1J1000D01*
G01X41484Y204810D01*
Y213658D01*
G03X41217Y214100I-500J0D01*
G02X44253I1518J2876D01*
G03X43986Y213658I233J-442D01*
G01Y210220D01*
G03X45633Y209457I1000J0D01*
G02X48695Y210083I2102J-2481D01*
G01X48828Y210042D01*
X49098Y210109D01*
X51484Y212495D01*
G03X51237Y214089I-707J707D01*
G02X53695Y220083I1497J2887D01*
G01X53828Y220042D01*
X54098Y220109D01*
X67826Y233836D01*
G03X67972Y234189I-354J353D01*
G01Y281593D01*
X41765Y307800D01*
G03X40058Y307092I-707J-707D01*
G01Y258258D01*
X51372Y246944D01*
X51642Y246877D01*
X51775Y246918D01*
G02X50633Y241330I960J-3107D01*
G03X48986Y240567I-647J-763D01*
G01Y237129D01*
G03X49253Y236687I500J0D01*
G02X46453Y230822I-1518J-2876D01*
G03X45058Y229903I-395J-919D01*
G01Y229702D01*
X41990Y226634D01*
X23143D01*
X19196Y230580D01*
G03X18695Y230704I-353J-354D01*
G02X20842Y232851I-960J3107D01*
G03X20966Y232350I478J-148D01*
G01X24033Y229282D01*
G03X24386Y229136I353J354D01*
G01X29433D01*
G03X29786Y229990I0J500D01*
G01X29098Y230678D01*
X28828Y230745D01*
X28695Y230704D01*
G02X30842Y232851I-960J3107D01*
G01X30801Y232718D01*
X30868Y232448D01*
X32634Y230682D01*
X34055D01*
G03X34920Y232182I-1J1000D01*
G02X34628Y234771I2815J1628D01*
G03X34504Y235272I-478J148D01*
G01X27458Y242319D01*
X27457Y245557D01*
G03X26604Y245910I-500J-1D01*
G01X25868Y245174D01*
X25801Y244904D01*
X25842Y244771D01*
G02X23695Y246918I-3107J-960D01*
G01X23828Y246877D01*
X24098Y246944D01*
X28848Y251694D01*
Y390587D01*
X20148Y399288D01*
G03X19795Y399434I-353J-354D01*
G01X17925D01*
G03X17361Y397608I0J-1000D01*
G02X11993Y399003I-4626J-6774D01*
G03X12610Y400706I-90J996D01*
G01X3644Y409673D01*
Y434667D01*
X26068Y457091D01*
Y480479D01*
X49486Y503898D01*
G03X48831Y505603I-707J707D01*
G02X52093Y508865I164J3098D01*
G03X53798Y508210I998J52D01*
G01X61722Y516134D01*
X63729D01*
X74414Y526819D01*
Y635230D01*
X42336Y667308D01*
X37150Y672495D01*
Y736804D01*
X36078Y737876D01*
X30815D01*
X29570Y739121D01*
G03X27871Y738542I-707J-707D01*
G02X23742Y740743I-2482J318D01*
G03X23791Y742203I-658J753D01*
G01X17418Y748576D01*
X14240D01*
X11857Y750959D01*
G03X10157Y750372I-707J-707D01*
G02X6025Y752553I-2484J299D01*
G03X6073Y754013I-659J752D01*
G01X3998Y756089D01*
Y794789D01*
X3538Y795249D01*
Y803414D01*
X3998Y803874D01*
Y803884D01*
X5064Y804951D01*
G03X5204Y805385I-353J354D01*
G02X9602Y804197I2469J405D01*
G01X11532D01*
Y807481D01*
X12938Y808888D01*
G03X13078Y809321I-354J353D01*
G01Y809322D01*
G02X13354Y810931I2469J405D01*
G03X12477Y812412I-877J481D01*
G01X10112D01*
G03X9705Y812204I-1J-500D01*
G02Y815124I-2032J1460D01*
G03X10112Y814916I406J292D01*
G01X12477D01*
G03X13354Y816397I0J1000D01*
G02Y818805I2193J1204D01*
G03X12477Y820286I-877J481D01*
G01X10112D01*
G03X9705Y820078I-1J-500D01*
G02Y822998I-2032J1460D01*
G03X10112Y822790I406J292D01*
G01X17064D01*
X21499Y818355D01*
G03X23115Y818645I707J707D01*
G02X25002Y815129I2274J-1044D01*
G03X23848Y814141I-154J-988D01*
G01Y813187D01*
G03X25002Y812199I1000J0D01*
G02Y807255I387J-2472D01*
G03X23848Y806267I-154J-988D01*
G01Y805313D01*
G03X25002Y804325I1000J0D01*
G02Y799381I387J-2472D01*
G03X23848Y798393I-154J-988D01*
G01Y789565D01*
G03X25002Y788577I1000J0D01*
G02X27422Y787564I387J-2472D01*
G03X27828Y787356I406J292D01*
G01X30193D01*
G03X31069Y788838I0J1000D01*
G02X35732Y789636I2194J1203D01*
G03X35872Y789202I493J-80D01*
G01X56226Y768847D01*
G03X57934Y769555I708J707D01*
G01Y775653D01*
G03X57788Y776006I-500J0D01*
G01X36973Y796820D01*
G03X35408Y796628I-708J-707D01*
G02X34489Y800096I-2145J1287D01*
G03X35980Y800967I491J871D01*
G01Y802738D01*
G03X34489Y803609I-1000J0D01*
G02Y807971I-1226J2181D01*
G03X35980Y808842I491J871D01*
G01Y810612D01*
G03X34489Y811483I-1000J0D01*
G02Y815845I-1226J2181D01*
G03X35980Y816716I491J871D01*
G01Y818486D01*
G03X34489Y819357I-1000J0D01*
G02Y823719I-1226J2181D01*
G03X35980Y824590I491J871D01*
G01Y826360D01*
G03X34489Y827231I-1000J0D01*
G02Y831593I-1226J2181D01*
G03X35980Y832464I491J871D01*
G01Y834234D01*
G03X34489Y835105I-1000J0D01*
G02Y839467I-1226J2181D01*
G03X35980Y840338I491J871D01*
G01Y842108D01*
G03X34489Y842979I-1000J0D01*
G02Y847341I-1226J2181D01*
G03X35980Y848212I491J871D01*
G01Y857856D01*
G03X34489Y858727I-1000J0D01*
G02X30830Y861490I-1226J2181D01*
G03X29943Y862719I-973J232D01*
G01X29027Y863635D01*
G03X27483Y863475I-707J-707D01*
G02X23031Y865682I-2094J1369D01*
G03X22089Y867016I-942J334D01*
G01X16072D01*
X15558Y867530D01*
X10112D01*
G03X9705Y867322I-1J-500D01*
G02Y870242I-2032J1460D01*
G03X10112Y870034I406J292D01*
G01X12477D01*
G03X13354Y871515I0J1000D01*
G02X13350Y873915I2193J1204D01*
G03X12471Y875394I-878J479D01*
G01X10103D01*
G03X9698Y875188I0J-500D01*
G02X9712Y878106I-2025J1469D01*
G03X10119Y877896I407J290D01*
G01X12483D01*
G03X13358Y879381I0J1000D01*
G02X14067Y882611I2189J1212D01*
G03X14183Y884124I-591J806D01*
G01X8512Y889795D01*
G03X8078Y889935I-354J-353D01*
G02X10142Y891999I-405J2469D01*
G03X10282Y891565I493J-80D01*
G01X12016Y889831D01*
G03X13529Y889947I707J707D01*
G02X18016Y888062I2018J-1480D01*
G01Y888061D01*
G03X18156Y887628I494J-80D01*
G01X19285Y886499D01*
G03X19638Y886352I354J353D01*
G01X22069D01*
G03X23017Y887671I0J1000D01*
G02X27421Y889927I2372J796D01*
G01X27492Y889828D01*
X27706Y889718D01*
X27827D01*
G03X28535Y891426I1J1000D01*
G01X26228Y893732D01*
G03X25794Y893872I-354J-353D01*
G02X23562Y898051I-405J2469D01*
G01X23701Y898199D01*
X23694Y898603D01*
X21104Y901193D01*
Y906318D01*
X24190Y909404D01*
X30824D01*
G03X31231Y909612I1J500D01*
G02Y906692I2032J-1460D01*
G03X30824Y906900I-406J-292D01*
G01X28459D01*
G03X27582Y905419I0J-1000D01*
G02X27858Y903810I-2193J-1204D01*
G03X27998Y903376I493J-80D01*
G01X29732Y901642D01*
G03X31245Y901758I707J707D01*
G02X35296Y901738I2018J-1480D01*
G03X35702Y901530I406J292D01*
G01X39689D01*
X63151Y878068D01*
X63767D01*
X68443Y873392D01*
G03X69835Y873371I707J707D01*
G02X71958Y871248I1030J-1093D01*
G03X71979Y869856I728J-685D01*
G01X92436Y849398D01*
G03X94144Y850106I708J707D01*
G01Y851561D01*
G03X93998Y851914I-500J0D01*
G01X78448Y867463D01*
Y914352D01*
X75161Y917640D01*
G03X74808Y917786I-353J-354D01*
G01X36682D01*
G03X35705Y916569I0J-1000D01*
G02X31202Y917444I-2442J-543D01*
G03X31144Y918081I-412J284D01*
G01X29475Y919750D01*
G03X27803Y919306I-707J-707D01*
G02X23321Y921371I-2414J657D01*
G03X22908Y922152I-413J281D01*
G01X22565D01*
X18690Y926028D01*
G03X17287Y926039I-707J-707D01*
G02X13354Y929041I-1740J1798D01*
G03X12477Y930522I-877J481D01*
G01X10112D01*
G03X9705Y930314I-1J-500D01*
G02Y933234I-2032J1460D01*
G03X10112Y933026I406J292D01*
G01X12477D01*
G03X13354Y934507I0J1000D01*
G02X13699Y937398I2193J1204D01*
G03X13684Y938089I-369J338D01*
G01X13533Y938239D01*
G03X13180Y938386I-354J-353D01*
G01X10103D01*
G03X9698Y938180I0J-500D01*
G02X9712Y941098I-2025J1469D01*
G03X10119Y940888I407J290D01*
G01X14423D01*
X15190Y940122D01*
X18611D01*
X22252Y936481D01*
G03X22959I353J354D01*
G01X23031Y936553D01*
X23069Y936648D01*
G02X23251Y937011I2320J-936D01*
G01Y937012D01*
G03X23178Y937625I-427J260D01*
G01X17208Y943595D01*
Y945315D01*
X16263Y946260D01*
X10103D01*
G03X9698Y946054I0J-500D01*
G02X9712Y948972I-2025J1469D01*
G03X10119Y948762I407J290D01*
G01X12483D01*
G03X13358Y950247I0J1000D01*
G02X18016Y951054I2189J1212D01*
G03X18156Y950620I493J-80D01*
G01X21452Y947324D01*
Y944923D01*
X21685Y944690D01*
G03X23248Y944880I707J707D01*
G02X27428Y945036I2141J-1295D01*
G03X27835Y944826I407J290D01*
G01X28144D01*
G03X28497Y945679I-1J500D01*
G01X27982Y946194D01*
Y954970D01*
X26228Y956724D01*
G03X25794Y956864I-354J-353D01*
G02X27858Y958928I-405J2469D01*
G03X27998Y958494I493J-80D01*
G01X29732Y956760D01*
G03X31245Y956876I707J707D01*
G02X31783Y957414I2018J-1480D01*
G03X31899Y958927I-591J806D01*
G01X26228Y964598D01*
G03X25794Y964738I-354J-353D01*
G02X27858Y966802I-405J2469D01*
G03X27998Y966368I493J-80D01*
G01X29732Y964634D01*
G03X31245Y964750I707J707D01*
G02X35302Y964720I2018J-1480D01*
G03X35709Y964510I407J290D01*
G01X62240D01*
X90962Y935788D01*
Y929616D01*
G03X92373Y928704I1000J0D01*
G02X94140Y926369I616J-1370D01*
G03X94200Y925020I767J-642D01*
G01X109244Y909975D01*
Y865434D01*
X112072Y862606D01*
Y796716D01*
G03X113322Y795747I1000J0D01*
G02Y792839I375J-1454D01*
G03X112072Y791870I-250J-969D01*
G01Y771509D01*
G03X112572Y771009I500J0D01*
G01X112600D01*
X112627Y771012D01*
G02X112836Y771024I213J-1890D01*
G01X115718D01*
G03X116612Y772472I0J1000D01*
G02X123228I3308J1662D01*
G03X124122Y771024I894J-448D01*
G01X126837D01*
X136982Y781168D01*
G03X137021Y781832I-353J354D01*
G01X137020Y781833D01*
G02X143204Y782424I2900J2301D01*
G03X144091Y780962I887J-462D01*
G01X150271D01*
X151721Y779512D01*
X156093D01*
G03X157080Y780674I0J1000D01*
G02X158956Y782884I1876J309D01*
G01X158990D01*
G03X159985Y783986I0J1000D01*
G02X160026Y784523I1494J156D01*
G03X159057Y785778I-967J255D01*
G02X160506Y786898I-4J1502D01*
G03X161475Y785643I967J-255D01*
G02X162973Y783986I4J-1502D01*
G03X163968Y782884I995J-102D01*
G01X174278D01*
X191440Y800046D01*
X213919D01*
X236447Y822574D01*
X252095D01*
X254492Y824971D01*
G02X257182Y822281I1345J-1345D01*
G01X253671Y818770D01*
X238023D01*
X237043Y817791D01*
G03X237397Y816938I354J-353D01*
G01X253631D01*
X257032Y813537D01*
G02X254342Y810847I-1345J-1345D01*
G01X252055Y813134D01*
X237155D01*
X216540Y792520D01*
X194897D01*
X178087Y775710D01*
X150145D01*
X148695Y777160D01*
X144163D01*
G03X143261Y775729I1J-1000D01*
G02X136369Y773087I-3341J-1594D01*
G03X134703Y773511I-959J-283D01*
G01X128413Y767220D01*
X124134D01*
G03X123238Y765777I0J-1000D01*
G02X116602I-3318J-1643D01*
G03X115706Y767220I-896J443D01*
G01X112836D01*
G02X112627Y767232I4J1902D01*
G01X112600Y767235D01*
X112572D01*
G03X112072Y766735I0J-500D01*
G01Y716876D01*
G03X112219Y716523I500J1D01*
G01X114570Y714172D01*
G03X116265Y714720I708J707D01*
G02X120506Y710479I3655J-586D01*
G03X119958Y708784I159J-987D01*
G01X121511Y707231D01*
G03X121864Y707084I354J353D01*
G01X245327D01*
X300000Y652412D01*
G03X301689Y652930I707J707D01*
G02X304619Y650000I2457J-473D01*
G03X304101Y648311I189J-982D01*
G01X312138Y640274D01*
X362669D01*
X399796Y603147D01*
Y421147D01*
X382357Y403708D01*
X382322Y403584D01*
G02X381293Y402555I-1444J415D01*
G01X381169Y402520D01*
X367248Y388600D01*
X357373D01*
X357120Y388347D01*
G03Y387639I353J-354D01*
G01X357247Y387512D01*
X357427Y387495D01*
G02X354408Y384203I-262J-2790D01*
G01X354376Y384381D01*
X354098Y384613D01*
X353916D01*
G03X353416Y384113I0J-500D01*
G01Y382504D01*
G03X353651Y382080I500J0D01*
G02X353191Y377098I-1486J-2375D01*
G03X352850Y375460I366J-931D01*
G01X352920Y375390D01*
G03X354558Y375731I707J707D01*
G02X354408Y374203I2607J-1027D01*
G01X354376Y374381D01*
X354098Y374613D01*
X353916D01*
G03X353416Y374113I0J-500D01*
G01Y372504D01*
G03X353651Y372080I500J0D01*
G02X350679I-1486J-2375D01*
G03X350914Y372504I-265J424D01*
G01Y373650D01*
G03X350767Y374003I-500J-1D01*
G01X350677Y374094D01*
G03X349970I-353J-354D01*
G01X349881Y374005D01*
X349845Y373886D01*
G02X344800Y373202I-2680J819D01*
G03X344378Y373434I-422J-268D01*
G01X342853D01*
G03X342353Y372934I0J-500D01*
G01Y372757D01*
X342575Y372482D01*
X342749Y372445D01*
G02X341581I-584J-2740D01*
G01X341582D01*
G03X341977Y372934I-105J489D01*
G01Y373142D01*
X341685Y373434D01*
X341640D01*
X341302Y373772D01*
G03X339693Y373496I-707J-707D01*
G02X336773Y377479I-2528J1209D01*
G01X336957Y377505D01*
X337202Y377787D01*
Y381623D01*
X336957Y381905D01*
X336773Y381931D01*
G02X335679Y387080I392J2774D01*
G03X335914Y387504I-265J424D01*
G01Y389159D01*
X347916Y401162D01*
X361449D01*
X362346Y402059D01*
X362381Y402183D01*
G02X363410Y403212I1444J-415D01*
G01X363534Y403247D01*
X389752Y429465D01*
Y598985D01*
X378427Y610310D01*
G03X376769Y609293I-707J-707D01*
G02X365356Y620706I-16927J-5514D01*
G03X366373Y622364I310J951D01*
G01X358507Y630230D01*
X312719D01*
G03X312011Y628523I-1J-1000D01*
G01X340402Y600132D01*
Y584600D01*
G03X340549Y584247I500J1D01*
G01X343191Y581605D01*
X343315Y581570D01*
G02X344344Y580541I-415J-1444D01*
G01X344379Y580417D01*
X363418Y561378D01*
Y557504D01*
G03X363653Y557080I500J0D01*
G02X362668Y551948I-1487J-2375D01*
G01X362490Y551916D01*
X362258Y551638D01*
Y551456D01*
G03X362758Y550956I500J0D01*
G01X363076D01*
X366750Y547283D01*
Y542699D01*
X362154Y538104D01*
X338100D01*
X328384Y547819D01*
Y583875D01*
X328322Y583988D01*
G02Y585442I1314J727D01*
G01X328384Y585555D01*
Y598485D01*
X239000Y687870D01*
G03X238647Y688016I-353J-354D01*
G01X100650D01*
X79758Y708908D01*
Y778132D01*
G03X78904Y778485I-500J0D01*
G01X78434Y778015D01*
Y707621D01*
X113718Y672336D01*
Y447114D01*
X92724Y426120D01*
Y423985D01*
G03X93973Y423017I1000J1D01*
G02X95791Y421977I374J-1455D01*
G01X95826Y421853D01*
X105951Y411728D01*
X116646D01*
G03X117342Y413445I-1J1000D01*
G02X122498I2578J2657D01*
G03X123194Y411728I697J-717D01*
G01X124199D01*
X128573Y407354D01*
X136101D01*
G03X136555Y407645I0J500D01*
G02Y404559I3365J-1543D01*
G03X136101Y404850I-454J-209D01*
G01X127537D01*
X125322Y407065D01*
G03X123617Y406303I-707J-707D01*
G02X116617Y407773I-3697J-201D01*
G03X115724Y409224I-892J451D01*
G01X107504D01*
G03X106684Y407653I1J-1000D01*
G02X105050Y408243I-1233J-858D01*
G01X105213Y408288D01*
X105417Y408556D01*
Y408724D01*
G03X104917Y409224I-500J0D01*
G01X104915D01*
X96346Y417793D01*
G03X94673Y417346I-707J-707D01*
G02X93224Y416234I-1450J390D01*
G03X92724Y415734I0J-500D01*
G01Y374007D01*
X106019Y360712D01*
X220304D01*
X303092Y277924D01*
X310405D01*
X341345Y246984D01*
G03X342999Y248015I708J707D01*
G02X368503Y238226I16843J5765D01*
G03X368989Y236352I486J-874D01*
G01X371977D01*
X400830Y207499D01*
Y71952D01*
X380734Y51855D01*
X380698Y51733D01*
G02X379682Y50717I-1441J425D01*
G01X379560Y50681D01*
X362835Y33956D01*
G03X363180Y32317I707J-707D01*
G02X359553Y28690I-1015J-2612D01*
G03X357914Y29035I-932J-362D01*
G01X357835Y28956D01*
G03X358180Y27317I707J-707D01*
G02X354553Y23690I-1015J-2612D01*
G03X352914Y24035I-932J-362D01*
G01X352835Y23956D01*
G03X353180Y22317I707J-707D01*
G02X349790Y18219I-1015J-2612D01*
G03X349366Y18454I-424J-265D01*
G01X346868D01*
X346379Y18943D01*
G03X344749Y18622I-707J-707D01*
G37*
G54D30*
X338309Y1927623D03*
X332399Y1926787D03*
X340336Y1922409D03*
X347676Y1922165D03*
X345537Y1916558D03*
X344402Y1911123D03*
X292614Y1864565D03*
X108819Y1824470D03*
X106819Y1802230D03*
X156452Y1800821D03*
X107373Y1780544D03*
X107355Y1770437D03*
X150309Y1737009D03*
X173394Y1736051D03*
X156183Y1735240D03*
X165782Y1732903D03*
X312077Y1575871D03*
X317243Y1574832D03*
X335963Y1573797D03*
X329399Y1571939D03*
X323720Y1570924D03*
X333474Y1566686D03*
X159526Y1483434D03*
X95236Y1453321D03*
X107006Y1452651D03*
X159192Y1451105D03*
X106763Y1444599D03*
X106962Y1434041D03*
X106921Y1419492D03*
X327932Y1289221D03*
X329619Y1284016D03*
X338047Y1282599D03*
X327452Y1279447D03*
X333242Y1276809D03*
X175897Y1023997D03*
X175359Y963486D03*
X175561Y955964D03*
X175989Y944537D03*
X176011Y936829D03*
X70865Y897750D03*
Y890116D03*
X329336Y762693D03*
X334010Y758588D03*
X327524Y758020D03*
X331568Y752967D03*
X339012Y752859D03*
X344109Y751809D03*
X156610Y751063D03*
X321742Y599041D03*
X319852Y593330D03*
X323751Y589155D03*
X317724Y588250D03*
X319305Y582111D03*
X320380Y576491D03*
X159019Y439268D03*
X109475Y434743D03*
X320980Y423225D03*
X323313Y418313D03*
X326196Y413982D03*
X328950Y409216D03*
X335522Y404033D03*
X342097Y401684D03*
X156865Y401207D03*
X106709Y391219D03*
X106836Y376461D03*
X107213Y85169D03*
X104350Y62293D03*
X338227Y61559D03*
X109054Y58250D03*
X345089Y56190D03*
X333889Y56021D03*
X340373Y51579D03*
X157558Y51426D03*
X331403Y51409D03*
X348289Y50863D03*
X107405Y49898D03*
X101430Y41803D03*
X107037Y34687D03*
X106958Y26285D03*
G54D21*
X270115Y2067489D03*
X258337D03*
X245582D03*
X234541D03*
X224573D03*
X270115Y2059050D03*
X258337D03*
X245582D03*
X234541D03*
X224573D03*
X270115Y2051322D03*
X258337D03*
X245582D03*
X234541D03*
X224573D03*
X270115Y2041985D03*
X258337D03*
X245582D03*
X234541D03*
X224573D03*
X270115Y2031480D03*
X258337D03*
X245582D03*
X234541D03*
X224573D03*
X270115Y2020965D03*
X258337D03*
X245582D03*
X234541D03*
X224573D03*
X314810Y1924283D03*
X307215D03*
X300349Y1924103D03*
X292754D03*
X314810Y1917328D03*
X307215D03*
X300349Y1917148D03*
X292754D03*
X314810Y1910412D03*
X307215D03*
X300349Y1910232D03*
X292754D03*
X267037Y1840093D03*
X258459Y1840090D03*
X250288D03*
X267037Y1833138D03*
X258459Y1833135D03*
X250288D03*
X267037Y1826222D03*
X258459Y1826219D03*
X250288D03*
X267396Y1819077D03*
X258639Y1819074D03*
X250468D03*
X267396Y1812122D03*
X258639Y1812119D03*
X250468D03*
X267396Y1805206D03*
X258639Y1805203D03*
X250468D03*
X265498Y1722140D03*
X254457D03*
X265759Y1714678D03*
X254718D03*
X265759Y1706950D03*
X254718D03*
X158492Y1703772D03*
X265759Y1697613D03*
X254718D03*
X158492Y1695333D03*
Y1687605D03*
X265759Y1687108D03*
X254718D03*
X158492Y1678268D03*
X265759Y1676593D03*
X254718D03*
X273342Y1668347D03*
X261564D03*
X158492Y1667763D03*
X273342Y1659908D03*
X261564D03*
X158492Y1657248D03*
X273342Y1652180D03*
X261564D03*
X273342Y1642843D03*
X261564D03*
X273342Y1632338D03*
X261564D03*
X273342Y1621823D03*
X261564D03*
X285995Y1548190D03*
X278400D03*
X271534Y1548010D03*
X263939D03*
X285995Y1541235D03*
X278400D03*
X271534Y1541055D03*
X263939D03*
X285995Y1534319D03*
X278400D03*
X271534Y1534139D03*
X263939D03*
X309464Y1493973D03*
X300886Y1493970D03*
X292715D03*
X309464Y1487018D03*
X300886Y1487015D03*
X292715D03*
X309464Y1480102D03*
X300886Y1480099D03*
X292715D03*
X309823Y1472957D03*
X301066Y1472954D03*
X292895D03*
X309823Y1466002D03*
X301066Y1465999D03*
X292895D03*
X309823Y1459086D03*
X301066Y1459083D03*
X292895D03*
X25393Y1388464D03*
X7677Y1384527D03*
X25393Y1380590D03*
X15551D03*
Y1372716D03*
X7677Y1368779D03*
X25393Y1364842D03*
Y1356968D03*
X7677Y1353031D03*
Y1337283D03*
Y1329409D03*
X33267Y1282165D03*
X25393Y1278228D03*
X15551D03*
X33267Y1274291D03*
X7677D03*
X15551Y1270354D03*
X33267Y1266417D03*
X15551Y1262480D03*
X33267Y1258543D03*
X7677D03*
X25393Y1254606D03*
X15551D03*
X7677Y1250669D03*
Y1242795D03*
X33267Y1203425D03*
X7677D03*
X25393Y1199488D03*
X15551D03*
X33267Y1195551D03*
X7677D03*
X15551Y1191614D03*
Y1183740D03*
X7677Y1179803D03*
Y1140432D03*
X25393Y1136496D03*
X15551D03*
X7677Y1132558D03*
Y1124684D03*
X15551Y1120748D03*
X7677Y1085314D03*
X15551Y1081377D03*
X7677Y1077440D03*
X15551Y1073503D03*
X33267Y1069566D03*
X15551Y1065629D03*
X7677Y1061692D03*
X318040Y1033718D03*
X306999D03*
X318170Y1027081D03*
X307129D03*
X318235Y1020657D03*
X307194D03*
X318184Y1014094D03*
X307143D03*
X318119Y1007303D03*
X307078D03*
X318315Y1001286D03*
X7673Y994766D03*
X274399Y990553D03*
X262621D03*
X274399Y982114D03*
X262621D03*
X33263Y979018D03*
X7673D03*
X25389Y975081D03*
X15547D03*
X274399Y974386D03*
X262621D03*
X7673Y971144D03*
X15547Y967207D03*
X274544Y967106D03*
X262766D03*
X274544Y959859D03*
X262766D03*
X15547Y959333D03*
X7673Y955396D03*
X274544Y949344D03*
X262766D03*
X15547Y919963D03*
X7673Y916026D03*
X15547Y912089D03*
X7673Y908152D03*
Y900278D03*
X15547Y896341D03*
X263174Y871326D03*
X251396D03*
X263174Y862887D03*
X251396D03*
X7673Y860908D03*
X25389Y856971D03*
X15547D03*
X263174Y855159D03*
X251396D03*
X25389Y849097D03*
X15547D03*
X7673Y845160D03*
X25389Y841223D03*
X15547D03*
X7673Y837286D03*
X25389Y833349D03*
X15547D03*
X7673Y829412D03*
X255021Y770949D03*
X243980D03*
X234012D03*
X255021Y762510D03*
X243980D03*
X234012D03*
X255021Y754782D03*
X243980D03*
X234012D03*
X7673Y742797D03*
X15547Y738860D03*
X25389Y730986D03*
X15547D03*
X33263Y727049D03*
X7673D03*
X33263Y719175D03*
X7673D03*
X25389Y715238D03*
X15547D03*
X33263Y711301D03*
X7673D03*
X25389Y707364D03*
X15547D03*
X33263Y703427D03*
X7673D03*
X315187Y697267D03*
X304146D03*
X315187Y688828D03*
X304146D03*
X315187Y681100D03*
X304146D03*
X315187Y671763D03*
X304146D03*
X315187Y661258D03*
X304146D03*
X315187Y652457D03*
X157272Y649583D03*
Y641144D03*
Y633416D03*
Y624079D03*
X278944Y617449D03*
X267166D03*
X157272Y613574D03*
X278944Y609010D03*
X267166D03*
X157272Y604773D03*
X278944Y601282D03*
X267166D03*
X278944Y591945D03*
X267166D03*
X278944Y581440D03*
X267166D03*
X278944Y572639D03*
X267166D03*
X316791Y532871D03*
X325139Y532799D03*
X292569Y532762D03*
X307966Y532586D03*
X300537Y532476D03*
X316791Y524432D03*
X325139Y524360D03*
X292569Y524323D03*
X307966Y524147D03*
X300537Y524037D03*
X316791Y516704D03*
X325139Y516632D03*
X292569Y516595D03*
X307966Y516419D03*
X300537Y516309D03*
X248714Y418041D03*
X239746Y417898D03*
X274531Y417794D03*
X266040Y417651D03*
X257572Y417650D03*
X248714Y407536D03*
X239746Y407393D03*
X274531Y407289D03*
X266040Y407146D03*
X257572Y407145D03*
X248714Y397021D03*
X239746Y396878D03*
X274531Y396774D03*
X266040Y396631D03*
X257572Y396630D03*
X343726Y348655D03*
X332685D03*
X343816Y342461D03*
X332775D03*
X343816Y335272D03*
X332775D03*
X343816Y325935D03*
X332775D03*
X343816Y318634D03*
X332775D03*
X165975Y312307D03*
X343734Y311980D03*
X332693D03*
X165975Y303868D03*
Y296140D03*
Y286803D03*
Y276298D03*
X264596Y268188D03*
X252818D03*
X165975Y265783D03*
X264596Y259749D03*
X252818D03*
X264596Y252021D03*
X252818D03*
X264596Y242684D03*
X252818D03*
X264596Y232179D03*
X252818D03*
X264596Y221664D03*
X252818D03*
X264861Y170131D03*
X253083D03*
X243741D03*
X232700D03*
X222732D03*
X264861Y161692D03*
X253083D03*
X243741D03*
X232700D03*
X222732D03*
X264861Y153964D03*
X253083D03*
X243741D03*
X232700D03*
X222732D03*
X288102Y65449D03*
X279754D03*
X271572D03*
X264104D03*
X256566D03*
X288102Y54944D03*
X279754D03*
X271572D03*
X264104D03*
X256566D03*
X288102Y45572D03*
X279754D03*
X271572D03*
X264104D03*
X256566D03*
G54D32*
X43995Y1622992D03*
X33995D03*
X23995D03*
X38995Y1612992D03*
X28995D03*
X18995D03*
X21495Y1571811D03*
X11692D03*
X61298Y559882D03*
X51495D03*
X21495D03*
X11692D03*
X53995Y518701D03*
X43995D03*
X33995D03*
X23995D03*
X38995Y508701D03*
X28995D03*
X18995D03*
G54D34*
X9606Y1499311D03*
Y1471949D03*
Y627264D03*
Y599901D03*
G54D27*
X323385Y1957520D03*
X313385D03*
X303385D03*
X293385D03*
X283385D03*
X273385D03*
X263385D03*
X253385D03*
X352165Y1954705D03*
X323385Y1946890D03*
X313385D03*
X303385D03*
X293385D03*
X283385D03*
X273385D03*
X263385D03*
X253385D03*
X357165Y1784705D03*
X323385Y1782520D03*
X313385D03*
X303385D03*
X293385D03*
X283385D03*
X273385D03*
X263385D03*
X253385D03*
X362165Y1779705D03*
X357165Y1774705D03*
X313385Y1771890D03*
X303385D03*
X293385D03*
X283385D03*
X273385D03*
X263385D03*
X253385D03*
X362165Y1769705D03*
X323385Y1607520D03*
X313385D03*
X303385D03*
X293385D03*
X283385D03*
X273385D03*
X263385D03*
X253385D03*
X352165Y1604705D03*
X342165D03*
X347165Y1599705D03*
X323385Y1596890D03*
X313385D03*
X303385D03*
X293385D03*
X283385D03*
X273385D03*
X263385D03*
X253385D03*
X323385Y1432520D03*
X313385D03*
X303385D03*
X293385D03*
X283385D03*
X273385D03*
X263385D03*
X253385D03*
X323385Y1421890D03*
X313385D03*
X303385D03*
X293385D03*
X283385D03*
X273385D03*
X263385D03*
X253385D03*
X313385Y907520D03*
X303385D03*
X293385D03*
X283385D03*
X273385D03*
X263385D03*
X253385D03*
X323385Y896890D03*
X313385D03*
X303385D03*
X293385D03*
X283385D03*
X273385D03*
X263385D03*
X253385D03*
X323386Y732520D03*
X313386D03*
X303386D03*
X293386D03*
X283386D03*
X273386D03*
X263386D03*
X253386D03*
X362166Y729705D03*
X323386Y721890D03*
X313386D03*
X303386D03*
X293386D03*
X283386D03*
X273386D03*
X263386D03*
X253386D03*
X362166Y719705D03*
X342166D03*
X323386Y557520D03*
X313386D03*
X303386D03*
X293386D03*
X283386D03*
X273386D03*
X263386D03*
X253386D03*
X323386Y546890D03*
X313386D03*
X303386D03*
X293386D03*
X283386D03*
X273386D03*
X263386D03*
X253386D03*
X323385Y382520D03*
X313385D03*
X303385D03*
X293385D03*
X283385D03*
X273385D03*
X263385D03*
X253385D03*
X362165Y379705D03*
X323385Y371890D03*
X313385D03*
X303385D03*
X293385D03*
X283385D03*
X273385D03*
X263385D03*
X253385D03*
X362165Y369705D03*
X323385Y207520D03*
X313385D03*
X303385D03*
X293385D03*
X283385D03*
X273385D03*
X263385D03*
X253385D03*
X323385Y196890D03*
X313385D03*
X303385D03*
X293385D03*
X283385D03*
X273385D03*
X263385D03*
X253385D03*
X323385Y32520D03*
X313385D03*
X303385D03*
X293385D03*
X283385D03*
X273385D03*
X263385D03*
X253385D03*
X337165Y24705D03*
X323385Y21890D03*
X313385D03*
X303385D03*
X293385D03*
X283385D03*
X273385D03*
X263385D03*
X253385D03*
X362165Y19705D03*
G54D23*
X205310Y2043388D03*
X205905Y1998730D03*
X204069Y1900420D03*
X205310Y1823227D03*
X205387Y1731351D03*
X205923Y1648177D03*
X204859Y1557277D03*
X203243Y1474162D03*
X210091Y947202D03*
X205386Y856244D03*
X205626Y774526D03*
X204596Y681645D03*
X206668Y598130D03*
X204333Y506517D03*
X203541Y421732D03*
X204137Y247568D03*
X204069Y152050D03*
X203542Y73105D03*
X52735Y34953D03*
X42735D03*
X22735D03*
X47735Y24953D03*
X27735D03*
X17735D03*
G54D22*
X139920Y2068228D03*
X119920D03*
X139920Y2058228D03*
X119920D03*
X139920Y2048228D03*
X119920D03*
X139920Y2038228D03*
X119920D03*
X139920Y2028228D03*
X119920D03*
X139920Y2018228D03*
X119920D03*
X139920Y2008228D03*
X119920D03*
X139920Y1998228D03*
X119920D03*
X139920Y1988228D03*
X119920D03*
X139920Y1978228D03*
X119920D03*
X139920Y1968228D03*
X119920D03*
X139920Y1958228D03*
X119920D03*
X139920Y1828228D03*
X119920D03*
X139920Y1798228D03*
X119920D03*
X139920Y1788228D03*
X119920D03*
X139920Y1778228D03*
X119920D03*
X139920Y1768228D03*
X119920D03*
Y1758228D03*
X139920Y1720197D03*
Y1710197D03*
Y1700197D03*
Y1690197D03*
Y1680197D03*
Y1670197D03*
Y1660197D03*
Y1650197D03*
Y1640197D03*
Y1630197D03*
Y1620197D03*
Y1610197D03*
X119920Y1480197D03*
X139920Y1460197D03*
Y1450197D03*
X119920D03*
X139920Y1440197D03*
X119920D03*
X139920Y1430197D03*
X119920D03*
X139920Y1420197D03*
X119920D03*
X139920Y954134D03*
X119920D03*
X139920Y944134D03*
X119920D03*
X139920Y934134D03*
X119920D03*
X139920Y924134D03*
X119920D03*
X139920Y914134D03*
X119920D03*
Y784134D03*
X139920Y764134D03*
Y754134D03*
X119920D03*
X139920Y744134D03*
X119920D03*
X139920Y734134D03*
X119920D03*
X139920Y724134D03*
X119920D03*
X139920Y714134D03*
Y676102D03*
X119920D03*
X139920Y666102D03*
X119920D03*
X139920Y656102D03*
X119920D03*
X139920Y646102D03*
X119920D03*
X139920Y636102D03*
X119920D03*
X139920Y626102D03*
X119920D03*
X139920Y616102D03*
X119920D03*
X139920Y606102D03*
X119920D03*
X139920Y596102D03*
X119920D03*
X139920Y586102D03*
X119920D03*
X139920Y576102D03*
X119920D03*
X139920Y566102D03*
X119920D03*
X139920Y416102D03*
Y396102D03*
Y386102D03*
X119920D03*
X139920Y376102D03*
X119920D03*
X139920Y366102D03*
X119920D03*
X139920Y328071D03*
X119920D03*
X139920Y318071D03*
X119920D03*
X139920Y308071D03*
X119920D03*
X139920Y298071D03*
X119920D03*
X139920Y288071D03*
X119920D03*
X139920Y278071D03*
X119920D03*
X139920Y268071D03*
X119920D03*
X139920Y258071D03*
X119920D03*
X139920Y248071D03*
X119920D03*
X139920Y238071D03*
X119920D03*
X139920Y228071D03*
X119920D03*
X139920Y218071D03*
X119920D03*
Y88071D03*
X139920Y68071D03*
Y58071D03*
X119920D03*
X139920Y48071D03*
X119920D03*
X139920Y38071D03*
X119920D03*
X139920Y28071D03*
X119920D03*
X139920Y18071D03*
X119920D03*
G54D31*
X45056Y1817693D03*
X23402D03*
X45056Y1801158D03*
Y1784622D03*
Y1768087D03*
X23402D03*
X45056Y1751551D03*
Y1735016D03*
Y1718480D03*
X23402D03*
X45056Y1701945D03*
Y1685410D03*
Y1668874D03*
X23402D03*
G54D35*
X20468Y696341D03*
G54D24*
X307087Y2043503D03*
Y1693503D03*
Y827164D03*
Y477164D03*
Y127164D03*
G54D36*
X307086Y308267D03*
G54D29*
X163385Y1952205D03*
Y1777205D03*
Y1602205D03*
Y1427205D03*
Y902205D03*
X163386Y727205D03*
Y552205D03*
X163385Y377205D03*
Y202205D03*
Y27205D03*
G54D25*
X57735Y2026661D03*
X12735D03*
X57735Y1922291D03*
X12735D03*
X57735Y268811D03*
X12735D03*
X57735Y181976D03*
X12735D03*
X57735Y59953D03*
X12735D03*
G54D28*
X373385Y1957520D03*
Y1607520D03*
Y1257520D03*
Y907520D03*
X373386Y732520D03*
Y557520D03*
X373385Y382520D03*
Y207520D03*
Y32520D03*
G54D33*
X13995Y1587992D03*
X58995Y543701D03*
X13995D03*
G54D26*
X359842Y2003780D03*
Y1828779D03*
Y1653780D03*
Y1478780D03*
Y1303780D03*
Y953780D03*
Y778780D03*
Y428779D03*
%LPD*%
G75*
G36*
G01X38600Y396687D02*
X24645Y410642D01*
X18526D01*
X18145Y411024D01*
G02X18589Y412696I707J707D01*
G03X16295Y418750I-855J3138D01*
G02X14852Y419647I-443J897D01*
G01Y430024D01*
X35452Y450624D01*
G02X36160I354J-354D01*
G01X57298Y429486D01*
Y418560D01*
X40308Y401570D01*
Y397395D01*
G02X38600Y396687I-1000J-1D01*
G37*
G36*
G01X30856Y743479D02*
G02X29186Y743044I-963J272D01*
G01X27838Y744392D01*
X25141D01*
X18454Y751080D01*
X15276D01*
X15102Y751254D01*
G02Y751961I354J353D01*
G01X15176Y752035D01*
X15367Y752110D01*
X15471Y752107D01*
G03X17372Y752896I76J2501D01*
G02X18809Y752920I730J-683D01*
G01X23384Y748344D01*
X27433D01*
X31057Y744720D01*
G02X31130Y744105I-353J-354D01*
G03X30856Y743479I2134J-1307D01*
G37*
G36*
G01X31090Y870757D02*
G02X31157Y870133I-353J-354D01*
G03X30907Y869624I2106J-1350D01*
G02X29258Y869253I-942J336D01*
G01X27691Y870820D01*
X19216D01*
X18156Y871880D01*
G02X18016Y872314I353J354D01*
G03X17985Y873281I-2469J405D01*
G02X18960Y874506I975J225D01*
G01X27342D01*
X31090Y870757D01*
G37*
G36*
G01X31295Y1004185D02*
G03X30970Y1003640I1969J-1544D01*
G02X29346Y1003333I-917J400D01*
G01X27764Y1004914D01*
X23391D01*
X23168Y1005138D01*
Y1008314D01*
G02X23668Y1008814I499J0D01*
G01X26196D01*
X30017Y1004994D01*
X30902D01*
G02X31295Y1004185I0J-500D01*
G37*
G36*
G01X18160Y1151405D02*
G02X18020Y1151839I353J354D01*
G03X18027Y1152602I-2469J404D01*
G02X19017Y1153746I990J144D01*
G01X27838D01*
X30873Y1150710D01*
X30946D01*
G02X31333Y1149893I1J-500D01*
G03X31019Y1149405I1933J-1589D01*
G02X29414Y1149137I-898J439D01*
G01X28464Y1150086D01*
X19478D01*
X18160Y1151405D01*
G37*
G36*
G01X23050Y1315902D02*
Y1317400D01*
X25227Y1319578D01*
X27873D01*
G02X28581Y1317870I1J-1000D01*
G01X26112Y1315402D01*
X23550D01*
G02X23050Y1315902I-1J499D01*
G37*
G36*
G01X36372Y236944D02*
X29960Y243355D01*
Y245012D01*
X32752Y247803D01*
Y248614D01*
G02X33605Y248967I500J-1D01*
G01X35192Y247381D01*
Y240269D01*
X37578Y237882D01*
G02Y237175I-353J-354D01*
G01X37459Y237056D01*
X37293Y237033D01*
G03X36775Y236918I443J-3222D01*
G01X36642Y236877D01*
X36372Y236944D01*
G37*
G36*
G01X86474Y641438D02*
G02X84766Y640731I-1000J0D01*
G01X48360Y677138D01*
Y688650D01*
G02X50067Y689358I1000J1D01*
G01X86474Y652951D01*
Y641438D01*
G37*
G36*
G01X32718Y764622D02*
X29265Y768076D01*
X27805D01*
G02X27403Y768872I0J500D01*
G03X27421Y768897I-2022J1475D01*
G02X27827Y769106I407J-291D01*
G01X34366D01*
X37142Y766330D01*
G02X36434Y764622I-707J-708D01*
G01X32718D01*
G37*
G36*
G01X32782Y890717D02*
X31166Y892333D01*
G02X31874Y894041I707J708D01*
G01X36321D01*
X37937Y892425D01*
G02X37229Y890717I-707J-708D01*
G01X32782D01*
G37*
G36*
G01X77722Y928780D02*
Y927549D01*
G02X76015Y926841I-1000J-1D01*
G01X72875Y929982D01*
X32158D01*
X28170Y933970D01*
X28122D01*
G02X27622Y934470I0J500D01*
G01Y934578D01*
X27667Y934676D01*
G03X27698Y934746I-2272J1048D01*
G02X29327Y935068I923J-385D01*
G01X30356Y934040D01*
X72463D01*
X77722Y928780D01*
G37*
G36*
G01X34102Y1013123D02*
G02X33668Y1012983I-354J353D01*
G03X30971Y1011516I-405J-2469D01*
G02X29347Y1011210I-916J401D01*
G01X27635Y1012922D01*
X27581Y1013234D01*
X27649Y1013378D01*
G03X27858Y1014856I-2260J1073D01*
G01X27838Y1014975D01*
X27912Y1015204D01*
X30830Y1018123D01*
Y1023066D01*
G02X32240Y1023979I1000J1D01*
G03X35732Y1026667I1023J2283D01*
G01X35712Y1026786D01*
X35786Y1027015D01*
X51292Y1042522D01*
X61086D01*
G02X61794Y1040814I1J-1000D01*
G01X34102Y1013123D01*
G37*
G36*
G01X74842Y1059307D02*
X43766Y1090383D01*
Y1093372D01*
X43134Y1094004D01*
X38107Y1099030D01*
X36582D01*
G02X35658Y1100325I32J1000D01*
G03X34802Y1103038I-2391J737D01*
G02X34684Y1104510I613J790D01*
G01X43182Y1113008D01*
X44248Y1114074D01*
X89917D01*
X105314Y1129471D01*
G02X106999Y1128973I707J-707D01*
G03X108781Y1130755I1469J313D01*
G02X108283Y1132440I209J978D01*
G01X117060Y1141217D01*
Y1257847D01*
G02X118455Y1258765I1000J0D01*
G03Y1265565I1465J3400D01*
G02X117060Y1266483I-395J918D01*
G01Y1267847D01*
G02X118455Y1268765I1000J0D01*
G03Y1275565I1465J3400D01*
G02X117060Y1276483I-395J918D01*
G01Y1277847D01*
G02X118455Y1278765I1000J0D01*
G03Y1285565I1465J3400D01*
G02X117060Y1286483I-395J918D01*
G01Y1287847D01*
G02X118455Y1288765I1000J0D01*
G03Y1295565I1465J3400D01*
G02X117060Y1296483I-395J918D01*
G01Y1297847D01*
G02X118455Y1298765I1000J0D01*
G03Y1305565I1465J3400D01*
G02X117060Y1306483I-395J918D01*
G01Y1307847D01*
G02X118455Y1308765I1000J0D01*
G03Y1315565I1465J3400D01*
G02X117060Y1316483I-395J918D01*
G01Y1317847D01*
G02X118455Y1318765I1000J0D01*
G03Y1325565I1465J3400D01*
G02X117060Y1326483I-395J918D01*
G01Y1327847D01*
G02X118455Y1328765I1000J0D01*
G03Y1335565I1465J3400D01*
G02X117060Y1336483I-395J918D01*
G01Y1337847D01*
G02X118455Y1338765I1000J0D01*
G03Y1345565I1465J3400D01*
G02X117060Y1346483I-395J918D01*
G01Y1347847D01*
G02X118455Y1348765I1000J0D01*
G03Y1355565I1465J3400D01*
G02X117060Y1356483I-395J918D01*
G01Y1357847D01*
G02X118455Y1358765I1000J0D01*
G03Y1365565I1465J3400D01*
G02X117060Y1366483I-395J918D01*
G01Y1367847D01*
G02X118455Y1368765I1000J0D01*
G03X123455Y1373263I1465J3400D01*
G03X120354Y1375841I-3535J-1098D01*
G01X120182Y1375862D01*
X120059Y1375984D01*
G02Y1376692I354J354D01*
G01X120662Y1377294D01*
X169496D01*
X177636Y1369154D01*
X238335D01*
X311628Y1295861D01*
Y1271321D01*
X317328Y1265621D01*
Y1244293D01*
X354430Y1207191D01*
Y1176640D01*
X325306Y1147516D01*
Y1127208D01*
X325244Y1127095D01*
G03Y1125641I1314J-727D01*
G01X325306Y1125528D01*
Y1110137D01*
X335767Y1099676D01*
G02X335914Y1099323I-353J-354D01*
G01Y1087504D01*
G02X335679Y1087080I-500J0D01*
G03X335550Y1082415I1486J-2375D01*
G03X339889Y1084047I1615J2290D01*
G01X339928Y1084208D01*
X340093Y1084346D01*
G02X340913Y1083962I320J-384D01*
G01X340914Y1082504D01*
G02X340679Y1082080I-500J0D01*
G03X341931Y1076913I1486J-2375D01*
G01X342117Y1076897D01*
X342600Y1076404D01*
Y1073006D01*
X342117Y1072513D01*
X341931Y1072497D01*
G03X340016Y1067907I234J-2792D01*
G03X343241Y1067118I2149J1798D01*
G03X344750Y1068624I-1076J2587D01*
G02X346372Y1068926I914J-405D01*
G01X346425Y1068873D01*
X346845Y1068454D01*
X349366D01*
G02X349790Y1068219I0J-500D01*
G03Y1071191I2375J1486D01*
G02X349366Y1070956I-424J265D01*
G01X347881D01*
X347697Y1071141D01*
X347673Y1071165D01*
G02X347897Y1072000I355J352D01*
G03X349748Y1073620I-732J2704D01*
G03X348651Y1077080I-2583J1085D01*
G02X348416Y1077504I265J424D01*
G01Y1079009D01*
G02X348564Y1079364I500J0D01*
G01X348581Y1079381D01*
G02X349288Y1079379I352J-355D01*
G01X349392Y1079274D01*
X349423Y1079129D01*
G03X350230Y1077679I2742J576D01*
G03X354367Y1077973I1935J2026D01*
G03X353651Y1082080I-2202J1732D01*
G02X353416Y1082504I265J424D01*
G01Y1084111D01*
G02X353916Y1084611I500J0D01*
G01X354098D01*
X354376Y1084380D01*
X354408Y1084201D01*
G03X355139Y1086641I2757J504D01*
G02X353416Y1087300I-723J691D01*
G01Y1102510D01*
X351567Y1104360D01*
X351335Y1104592D01*
X351299Y1104716D01*
G03X350269Y1105746I-1444J-414D01*
G01X350145Y1105782D01*
X338437Y1117490D01*
G02X338290Y1117843I353J354D01*
G01Y1145519D01*
X365022Y1172251D01*
Y1210190D01*
G02X366704Y1210890I1000J-32D01*
G01X370272Y1207323D01*
Y1205565D01*
X370209Y1205452D01*
G03Y1203998I1314J-727D01*
G01X370272Y1203885D01*
Y1152675D01*
X387724Y1135222D01*
Y1080001D01*
X371620Y1063897D01*
G02X371267Y1063750I-354J353D01*
G01X283391D01*
X278801Y1059160D01*
X144142D01*
G02X143269Y1060587I31J1000D01*
G03X136571I-3349J1578D01*
G02X135698Y1059160I-904J-427D01*
G01X124142D01*
G02X123269Y1060587I31J1000D01*
G03X116571I-3349J1578D01*
G02X115698Y1059160I-904J-427D01*
G01X85231D01*
G02X84264Y1060117I32J1000D01*
G03X81262I-1501J-66D01*
G02X80295Y1059160I-999J43D01*
G01X75195D01*
G02X74842Y1059307I1J500D01*
G37*
G36*
G01X29345Y1096514D02*
X30636Y1095224D01*
X36207D01*
X39466Y1091964D01*
Y1091580D01*
G02X38966Y1091080I-499J0D01*
G01X32094D01*
X28385Y1094789D01*
G02X27698Y1096151I234J972D01*
G03X27711Y1096184I-2321J933D01*
G02X29345Y1096514I926J-377D01*
G37*
G36*
G01X35681Y1234264D02*
G03X35736Y1235326I-2414J657D01*
G02X35876Y1235760I493J80D01*
G01X47698Y1247582D01*
Y1248271D01*
X56360Y1256933D01*
G02X57891Y1256794I708J-707D01*
G03X59980Y1258883I1236J853D01*
G02X59841Y1260414I568J823D01*
G01X75440Y1276013D01*
G02X77122Y1275281I682J-731D01*
G01Y1262087D01*
X48063Y1233028D01*
X36653D01*
G02X35681Y1234264I0J1000D01*
G37*
G36*
G01X47120Y1549749D02*
G02X45412Y1550457I-708J707D01*
G01Y1591139D01*
X67688Y1613415D01*
Y1613842D01*
G02X69396Y1614550I1000J1D01*
G01X72842Y1611103D01*
Y1575472D01*
X47120Y1549749D01*
G37*
G36*
G01X34798Y1947584D02*
X41274Y1954060D01*
G02X41775Y1954184I353J-354D01*
G03X45597Y1958835I960J3107D01*
G02X46477Y1960310I880J475D01*
G01X48993D01*
G02X49873Y1958835I0J-1000D01*
G03X49628Y1956331I2862J-1544D01*
G01X49669Y1956198D01*
X49602Y1955928D01*
X40730Y1947056D01*
Y1944240D01*
X33702Y1937211D01*
G02X31994Y1937919I-708J707D01*
G01Y1939610D01*
X34798Y1942413D01*
Y1947584D01*
G37*
G36*
G01X191534Y1028332D02*
X188887Y1030978D01*
X177941D01*
G02X176945Y1031894I0J1000D01*
G03X173951I-1497J-128D01*
G02X172955Y1030978I-996J84D01*
G01X69867D01*
G02X69159Y1032686I-1J1000D01*
G01X72058Y1035584D01*
X205566D01*
G02X206443Y1034105I0J-1000D01*
G03X207166Y1030087I2853J-1561D01*
G02X206510Y1028332I-656J-755D01*
G01X191534D01*
G37*
G36*
G01X67342Y1306344D02*
G03Y1309314I226J1485D01*
G02X66192Y1310303I-150J988D01*
G01Y1457334D01*
X75380Y1466523D01*
G02X77088Y1465815I708J-707D01*
G01Y1384211D01*
X75822Y1382946D01*
Y1319895D01*
X72474Y1316546D01*
Y1314060D01*
X75822Y1310711D01*
Y1279935D01*
X67899Y1272011D01*
G02X66192Y1272719I-707J707D01*
G01Y1305355D01*
G02X67342Y1306344I1000J1D01*
G37*
G36*
G01X61754Y1270958D02*
Y1298126D01*
X61981Y1298354D01*
G02X63689Y1297646I708J-707D01*
G01X63688Y1270478D01*
X63461Y1270250D01*
G02X61754Y1270958I-707J707D01*
G37*
G36*
G01X111072Y699544D02*
X93750Y716866D01*
Y749186D01*
G02X95160Y750099I1000J1D01*
G03X97253Y751200I615J1370D01*
G02X98944Y751728I984J-179D01*
G01X100600Y750072D01*
Y713992D01*
X113341Y701252D01*
G02X112633Y699544I-707J-708D01*
G01X111072D01*
G37*
G36*
G01X100889Y755163D02*
X100312Y755739D01*
Y781043D01*
X100889Y781619D01*
G02X101742Y781266I353J-354D01*
G01Y755516D01*
G02X100889Y755163I-500J1D01*
G37*
G36*
G01X182632Y1377790D02*
X177732Y1382690D01*
G02X178440Y1384398I707J708D01*
G01X200844D01*
G02X201664Y1382826I0J-1000D01*
G03X201538Y1379302I2668J-1860D01*
G02X200679Y1377790I-859J-512D01*
G01X182632D01*
G37*
G36*
G01X265586Y1388364D02*
X264030Y1389919D01*
G02X264738Y1391626I707J707D01*
G01X293910D01*
G02X294618Y1389919I1J-1000D01*
G01X293062Y1388364D01*
X265586D01*
G37*
%LPC*%
G75*
G36*
G01X137114Y1089750D02*
G03X136735Y1089924I-379J-326D01*
G01X136528D01*
X136236Y1089632D01*
Y1088954D01*
X123531Y1076250D01*
X123469D01*
G03X122714Y1074594I0J-1000D01*
G02X117126I-2794J-2429D01*
G03X116371Y1076250I-755J656D01*
G01X96357D01*
X93346Y1079260D01*
Y1083882D01*
X95778Y1086314D01*
X107895D01*
X113959Y1092377D01*
G02X114471Y1092748I1416J-1415D01*
G03X114838Y1094216I-451J893D01*
G02X114474Y1095366I1638J1151D01*
G01Y1098964D01*
G02X115930Y1100889I2002J-1D01*
G03X116285Y1101465I-136J481D01*
G02Y1102865I3635J700D01*
G03X115930Y1103441I-491J95D01*
G02X114474Y1105366I546J1926D01*
G01Y1108964D01*
G02X115930Y1110889I2002J-1D01*
G03X116285Y1111465I-136J481D01*
G02Y1112865I3635J700D01*
G03X115930Y1113441I-491J95D01*
G02X114770Y1114319I545J1926D01*
G03X113352Y1114621I-852J-523D01*
G02X113086Y1117244I-849J1239D01*
G03X114474Y1118166I388J922D01*
G01Y1118964D01*
G02X115930Y1120889I2002J-1D01*
G03X116285Y1121465I-136J481D01*
G02X117522Y1124985I3635J700D01*
G03X117645Y1125590I-324J381D01*
G02X117926Y1127324I1342J672D01*
G01X118097Y1127495D01*
G03X117928Y1129045I-707J707D01*
G02X122572Y1129582I1992J3120D01*
G03X123289Y1127884I716J-698D01*
G01X136551D01*
G03X137268Y1129582I1J1000D01*
G02X141536Y1128834I2652J2583D01*
G01X141406Y1128771D01*
X141254Y1128529D01*
Y1128384D01*
G03X141754Y1127884I500J0D01*
G01X142287D01*
X145402Y1124769D01*
Y1117826D01*
X142790Y1115214D01*
G03X142760Y1114540I354J-353D01*
G02X137806Y1109126I-2840J-2375D01*
G03X136236Y1108305I-570J-821D01*
G01Y1106025D01*
G03X137806Y1105204I1000J0D01*
G02Y1099126I2114J-3039D01*
G03X136236Y1098305I-570J-821D01*
G01Y1096025D01*
G03X137806Y1095204I1000J0D01*
G02X137114Y1089750I2114J-3039D01*
G37*
G54D30*
X57124Y675327D03*
X54483Y679810D03*
X59236Y670758D03*
X107351Y1093484D03*
X107215Y1072208D03*
X108779Y1105760D03*
X105152Y1118381D03*
X156854Y1101031D03*
X159382Y1136151D03*
X158456Y1129045D03*
X312527Y1162266D03*
X312698Y1172804D03*
X323403D03*
X49441Y1238962D03*
G54D21*
X155749Y1307733D03*
Y1328753D03*
Y1318248D03*
Y1354257D03*
Y1338090D03*
Y1345818D03*
X219214Y1287272D03*
Y1301975D03*
X219349Y1308924D03*
X219214Y1294491D03*
X219178Y1324285D03*
Y1332321D03*
Y1316842D03*
Y1339840D03*
X226642Y1287272D03*
Y1301975D03*
X235465D03*
X226777Y1308924D03*
X235600D03*
X242961Y1301975D03*
X243096Y1308924D03*
X226642Y1294491D03*
X235465D03*
X242961D03*
X226606Y1324285D03*
X235429D03*
X226606Y1332321D03*
X235429D03*
X242925Y1324285D03*
Y1332321D03*
X226606Y1316842D03*
X235429D03*
X242925D03*
X226606Y1339840D03*
X235429D03*
X242925D03*
X261219Y1124364D03*
Y1134879D03*
X251251Y1124364D03*
Y1134879D03*
X261219Y1145384D03*
X251251D03*
X259581Y1272430D03*
Y1282945D03*
Y1293450D03*
Y1302787D03*
Y1310515D03*
Y1318954D03*
X279015Y1124077D03*
X288363Y1123935D03*
X279015Y1134592D03*
X288363Y1134450D03*
X269975Y1134735D03*
Y1124220D03*
X288363Y1144955D03*
X279015Y1145097D03*
X269975Y1145240D03*
X286721Y1184312D03*
Y1192040D03*
X278182Y1184455D03*
Y1192183D03*
X286721Y1200479D03*
X278182Y1200622D03*
X270622Y1282945D03*
Y1272430D03*
Y1293450D03*
Y1302787D03*
Y1310515D03*
Y1318954D03*
X303159Y1184526D03*
Y1192254D03*
X311936Y1192253D03*
Y1184525D03*
X294691Y1184526D03*
Y1192254D03*
X311936Y1200692D03*
X303159Y1200693D03*
X294691D03*
G54D32*
X51495Y1571811D03*
X61298D03*
G54D27*
X253385Y1071890D03*
X263385D03*
X253385Y1082520D03*
X263385D03*
X253385Y1246890D03*
Y1257520D03*
X263385Y1246890D03*
Y1257520D03*
X273385Y1071890D03*
X283385D03*
X273385Y1082520D03*
X283385D03*
X273385Y1246890D03*
Y1257520D03*
X283385Y1246890D03*
Y1257520D03*
X293385Y1071890D03*
X303385D03*
X313385D03*
X293385Y1082520D03*
X303385D03*
X313385D03*
X293385Y1246890D03*
Y1257520D03*
X303385Y1246890D03*
Y1257520D03*
X313385D03*
Y1246890D03*
X323385Y1071890D03*
X337165Y1074705D03*
X323385Y1082520D03*
X362165Y1069705D03*
X357165Y1074705D03*
X362165Y1079705D03*
G54D23*
X27735Y415834D03*
X22735Y425834D03*
X47735Y415834D03*
X42735Y425834D03*
X32735D03*
X52735D03*
X205030Y1122856D03*
X205122Y1206233D03*
X205626Y1299104D03*
G54D22*
X139920Y1072165D03*
Y1082165D03*
Y1262165D03*
Y1282165D03*
Y1272165D03*
Y1312165D03*
Y1302165D03*
Y1292165D03*
Y1332165D03*
Y1322165D03*
Y1362165D03*
Y1352165D03*
Y1342165D03*
Y1372165D03*
G54D37*
X163385Y1252205D03*
Y1077205D03*
G54D28*
X373385Y1082520D03*
G54D33*
X58995Y1587992D03*
G54D26*
X359842Y1128779D03*
%LPD*%
G75*
G36*
G01X96772Y1077251D02*
X94348Y1079675D01*
Y1083467D01*
X96193Y1085312D01*
X108310D01*
X114667Y1091669D01*
G02X116341Y1091218I707J-707D01*
G03X117208Y1094685I3579J947D01*
G02X115476Y1095366I-732J681D01*
G01Y1098964D01*
G02X117208Y1099645I1000J0D01*
G03Y1104685I2712J2520D01*
G02X115476Y1105366I-732J681D01*
G01Y1108964D01*
G02X117208Y1109645I1000J0D01*
G03Y1114685I2712J2520D01*
G02X115476Y1115366I-732J681D01*
G01Y1118964D01*
G02X117208Y1119645I1000J0D01*
G03X119098Y1125775I2712J2520D01*
G01X118972Y1125746D01*
X118725Y1125817D01*
X118634Y1125909D01*
G02Y1126616I353J353D01*
G01X118901Y1126883D01*
X141872D01*
X144401Y1124354D01*
Y1118241D01*
X142505Y1116345D01*
X136498D01*
X135234Y1115081D01*
Y1089369D01*
X123116Y1077251D01*
X96772D01*
G37*
%LPC*%
G75*
G54D30*
X107235Y1081791D03*
G54D22*
X119920Y1082165D03*
%LPD*%
G75*
G54D10*
G01X111017Y419566D02*
Y424690D01*
X117506Y431179D01*
X148139D01*
X150507Y428811D01*
X221508D01*
X258946Y466249D01*
X262575D01*
X265722Y463102D01*
G01X158807Y432969D02*
X219785D01*
X257131Y470315D01*
X262372D01*
X265737Y473680D01*
X25219Y18752D03*
X3001Y52034D03*
Y100034D03*
Y150034D03*
Y200034D03*
Y250034D03*
Y300034D03*
Y350034D03*
Y400034D03*
Y450034D03*
Y500034D03*
Y550034D03*
X11677Y578766D03*
X3001Y600034D03*
Y650034D03*
Y700034D03*
Y750034D03*
Y800034D03*
Y850034D03*
Y900034D03*
Y950034D03*
Y1000034D03*
Y1050034D03*
Y1100034D03*
Y1150034D03*
Y1200034D03*
Y1250034D03*
Y1300034D03*
Y1350034D03*
Y1400034D03*
Y1450034D03*
Y1500034D03*
Y1550034D03*
X16484Y1552159D03*
X11085Y1552589D03*
X3006Y1594602D03*
X3012Y1610165D03*
X3001Y1650034D03*
Y1700034D03*
Y1750034D03*
Y1800034D03*
Y1850034D03*
Y1900034D03*
Y1950034D03*
Y2000034D03*
Y2050034D03*
X48433Y866179D03*
X48467Y869278D03*
X26833Y2067866D03*
X58750Y579653D03*
X63820Y579654D03*
X61888Y666012D03*
X60815Y1019026D03*
X63577Y1019115D03*
X57458Y1253378D03*
X54543Y1296513D03*
X63061Y1296312D03*
X67568Y1296654D03*
X54108Y1559138D03*
X75219Y18752D03*
X97417Y32853D03*
Y37438D03*
X97536Y376580D03*
X97457Y371909D03*
X97985Y391220D03*
X97643Y396024D03*
X94347Y421562D03*
X98591Y720745D03*
X98564Y715937D03*
X97443Y739962D03*
X97534Y735248D03*
X98124Y745139D03*
X76446Y1014871D03*
X79499D03*
X96904Y1067515D03*
X96948Y1092036D03*
X96949Y1087095D03*
X96774Y1072226D03*
X96684Y1081791D03*
X96510Y1395382D03*
X97403Y1424340D03*
X97825Y1419492D03*
X96993Y1443743D03*
X96996Y1438980D03*
X97465Y1447919D03*
X76833Y2067866D03*
X106335Y22580D03*
X108082Y38899D03*
X102646Y49461D03*
X107263Y72244D03*
X104116Y82557D03*
X101990Y426104D03*
X111017Y419566D03*
X101244Y774100D03*
X112836Y769122D03*
X105395Y972040D03*
X102611Y972220D03*
X98652Y1096403D03*
X105684Y1125919D03*
X101626Y1397635D03*
X105455Y1472894D03*
X108574Y1463389D03*
X99103Y1765722D03*
X99068Y1760827D03*
X99047Y1785571D03*
X98873Y1780542D03*
X99294Y1789947D03*
X105669Y1815227D03*
X108819Y1812118D03*
X109991Y2083607D03*
X125219Y3002D03*
X162384Y56744D03*
X161742Y72497D03*
X162586Y68130D03*
X158901Y85017D03*
X161377Y407575D03*
X161257Y420869D03*
X158807Y432969D03*
X161826Y756757D03*
X161131Y774878D03*
X161644Y764231D03*
X158956Y780982D03*
X164539Y1116135D03*
X162140Y1106853D03*
X163099Y1457084D03*
X162524Y1462651D03*
X162242Y1471380D03*
X159216Y1477124D03*
X163250Y1815631D03*
X162140Y1807740D03*
X159075Y1825087D03*
X159991Y2083607D03*
X175219Y3002D03*
X184284Y948331D03*
X184196Y967371D03*
X175135Y972490D03*
X184632Y983423D03*
X175022Y980281D03*
X175742Y989958D03*
X175449Y997660D03*
X184353Y1001556D03*
X184118Y1019280D03*
X188385Y1020810D03*
X175698Y1008730D03*
X175473Y1016296D03*
X209991Y2083607D03*
X225219Y3002D03*
X267627Y115559D03*
X256947Y128276D03*
X257125Y115559D03*
X265722Y463102D03*
X265737Y473680D03*
X255837Y823626D03*
X255687Y812192D03*
X259991Y2083607D03*
X275219Y3002D03*
X287420Y162540D03*
X283086Y162675D03*
X271547Y245353D03*
X276617Y241400D03*
X281193Y241624D03*
X285513Y337688D03*
X281074D03*
X289895D03*
X286665Y417844D03*
X291002D03*
X281569Y421169D03*
X274991Y463099D03*
X282776Y512341D03*
X278405D03*
X273938D03*
X269516D03*
X285348Y595540D03*
X290984Y592215D03*
X274514Y687192D03*
X270109D03*
X283340D03*
X278955D03*
X273114Y770968D03*
X278184Y767643D03*
X282737D03*
X270070Y812192D03*
X276686Y862488D03*
X272181Y862354D03*
X285788Y862237D03*
X281305D03*
X275966Y944767D03*
X281194Y941442D03*
X285874D03*
X285666Y1031162D03*
X281124D03*
X290107D03*
X282958Y1119471D03*
X288188Y1116146D03*
X289082Y1206777D03*
X284194D03*
X279559D03*
X283808Y1293959D03*
X289210Y1290634D03*
X284240Y1389544D03*
X279518Y1389543D03*
X275052Y1389715D03*
X270579Y1389626D03*
X270234Y1467760D03*
X275521Y1464435D03*
X279990D03*
X289675Y1558211D03*
X285054D03*
X284086Y1644883D03*
X289421Y1641558D03*
X274704Y1738196D03*
X279703Y1738398D03*
X284583Y1738465D03*
X289499Y1738735D03*
X281066Y1819569D03*
X291550Y1814846D03*
X286623Y1814400D03*
X280240Y1858668D03*
X279976Y1864565D03*
X287121Y1913327D03*
X282717D03*
X278262D03*
X273817D03*
X299687Y63778D03*
X304151D03*
X308651D03*
X313089D03*
X294483Y67732D03*
X296523Y162585D03*
X291943Y162630D03*
X314914Y238162D03*
X294506Y337688D03*
X295509Y592215D03*
X294617Y1031162D03*
X292698Y1116146D03*
X293807Y1206777D03*
X294133Y1290634D03*
X314183Y1403423D03*
X313894Y1513883D03*
X302267Y1524401D03*
X301734Y1513883D03*
X298870Y1558211D03*
X294392D03*
X294090Y1641558D03*
X311539Y1753499D03*
X293606Y1858668D03*
X314562Y1994087D03*
X309991Y2083607D03*
X325219Y3002D03*
X322005Y63778D03*
X317567D03*
X320372Y225979D03*
X318088Y231820D03*
X321899Y238137D03*
X331046Y232021D03*
X324709Y231580D03*
X336617Y577978D03*
X329636Y584715D03*
X337387Y586230D03*
X331867Y589810D03*
X333750Y595326D03*
X329938Y948756D03*
X332527Y943746D03*
X318557Y941178D03*
X323868Y929978D03*
X336160Y937262D03*
X331920Y1116088D03*
X337509Y1109598D03*
X328989Y1121090D03*
X326558Y1126368D03*
X325796Y1162266D03*
X319404Y1401346D03*
X325636Y1399114D03*
X329887Y1752081D03*
X321283Y1753466D03*
X335730Y1753270D03*
X324803Y1990272D03*
X320045Y1990215D03*
X359931Y52189D03*
X363825Y401768D03*
X342900Y580126D03*
X362577Y752783D03*
X343656Y933725D03*
X344099Y1106798D03*
X349855Y1104302D03*
X350690Y1403243D03*
X348710Y1570187D03*
X361011Y1568890D03*
X343402Y1572080D03*
X348245Y1575241D03*
X355364Y1570990D03*
X363361Y1918313D03*
X358318Y1920680D03*
X363411Y1923459D03*
X359991Y2083607D03*
X375219Y3002D03*
X372204Y56126D03*
X365720Y52336D03*
X379257Y52158D03*
X379572Y58441D03*
X387524Y76847D03*
X374442Y406857D03*
X380619Y410112D03*
X380878Y403999D03*
X374542Y401282D03*
X368907Y404308D03*
X376654Y754748D03*
X382892Y767710D03*
X386790Y774338D03*
X380186Y761742D03*
X379335Y1189778D03*
X383276Y1184136D03*
X386816Y1179841D03*
X376472Y1194999D03*
X373674Y1199967D03*
X371523Y1204725D03*
X367829Y1566108D03*
X374775Y1919243D03*
X379403Y1917261D03*
X369748Y1921795D03*
X402512Y17108D03*
Y67108D03*
Y117108D03*
Y167108D03*
Y217108D03*
Y267108D03*
Y317108D03*
Y367108D03*
Y417108D03*
Y467108D03*
Y517108D03*
Y567108D03*
Y617108D03*
Y667108D03*
Y717108D03*
Y767108D03*
X391278Y765894D03*
X402512Y817108D03*
Y867108D03*
Y917108D03*
Y967108D03*
Y1017108D03*
Y1067108D03*
Y1117108D03*
Y1167108D03*
Y1217108D03*
Y1267108D03*
Y1317108D03*
Y1367108D03*
Y1417108D03*
Y1467108D03*
Y1517108D03*
Y1567108D03*
Y1617108D03*
Y1667108D03*
Y1717108D03*
Y1767108D03*
Y1817108D03*
Y1867108D03*
Y1917108D03*
Y1967108D03*
Y2017108D03*
Y2067108D03*
G54D20*
G01X-723776Y2987387D02*
Y-376795D01*
Y-489221D01*
X1782976D01*
Y-376795D01*
Y2987387D01*
X-723776D01*
G01X-4000Y-62500D02*
Y-137500D01*
X496000D01*
Y-62500D01*
X-4000D01*
G01X8000Y-127500D02*
Y-132500D01*
G01X6543Y-127500D02*
X9457D01*
G01X14367Y-132500D02*
X11833D01*
Y-127500D01*
X14367D01*
G01X13353Y-129917D02*
X11833D01*
G01X16933Y-127500D02*
Y-132500D01*
X19467D01*
G01X23300Y-132667D02*
X23173Y-132583D01*
Y-132417D01*
X23300Y-132333D01*
X23427Y-132417D01*
Y-132583D01*
X23300Y-132667D01*
G01Y-130417D02*
X23173Y-130333D01*
Y-130167D01*
X23300Y-130083D01*
X23427Y-130167D01*
Y-130333D01*
X23300Y-130417D01*
G01X28083Y-134167D02*
X27450Y-133333D01*
X27133Y-132500D01*
Y-129167D01*
X27450Y-128333D01*
X28083Y-127500D01*
G01X33500D02*
X32993Y-127667D01*
X32613Y-128083D01*
X32360Y-128583D01*
X32170Y-129250D01*
X32107Y-130000D01*
X32170Y-130750D01*
X32360Y-131417D01*
X32613Y-131917D01*
X32993Y-132333D01*
X33500Y-132500D01*
X34007Y-132333D01*
X34387Y-131917D01*
X34640Y-131417D01*
X34830Y-130750D01*
X34893Y-130000D01*
X34830Y-129250D01*
X34640Y-128583D01*
X34387Y-128083D01*
X34007Y-127667D01*
X33500Y-127500D01*
G01X37207Y-131500D02*
X37587Y-132083D01*
X38093Y-132417D01*
X38663Y-132500D01*
X39170Y-132417D01*
X39677Y-132000D01*
X39993Y-131500D01*
X40057Y-131000D01*
X39930Y-130417D01*
X39487Y-130000D01*
X39043Y-129833D01*
X38473D01*
G01X39043D02*
X39423Y-129583D01*
X39740Y-129167D01*
X39867Y-128667D01*
X39740Y-128167D01*
X39423Y-127750D01*
X38853Y-127500D01*
X38283Y-127583D01*
X37713Y-127917D01*
G01X44017Y-134167D02*
X44650Y-133333D01*
X44967Y-132500D01*
Y-129167D01*
X44650Y-128333D01*
X44017Y-127500D01*
G01X47407Y-131500D02*
X47787Y-132083D01*
X48293Y-132417D01*
X48863Y-132500D01*
X49370Y-132417D01*
X49877Y-132000D01*
X50193Y-131500D01*
X50257Y-131000D01*
X50130Y-130417D01*
X49687Y-130000D01*
X49243Y-129833D01*
X48673D01*
G01X49243D02*
X49623Y-129583D01*
X49940Y-129167D01*
X50067Y-128667D01*
X49940Y-128167D01*
X49623Y-127750D01*
X49053Y-127500D01*
X48483Y-127583D01*
X47913Y-127917D01*
G01X52697Y-128333D02*
X53077Y-127833D01*
X53520Y-127583D01*
X54027Y-127500D01*
X54660Y-127667D01*
X55103Y-128083D01*
X55230Y-128583D01*
X55167Y-129083D01*
X54913Y-129500D01*
X53647Y-130333D01*
X53077Y-130917D01*
X52697Y-131750D01*
X52570Y-132500D01*
X55230D01*
G01X58873D02*
X59000Y-131417D01*
X59190Y-130500D01*
X59443Y-129667D01*
X59760Y-128750D01*
X60267Y-127500D01*
X57733D01*
G01X63277Y-130833D02*
X64923D01*
G01X67997Y-128333D02*
X68377Y-127833D01*
X68820Y-127583D01*
X69327Y-127500D01*
X69960Y-127667D01*
X70403Y-128083D01*
X70530Y-128583D01*
X70467Y-129083D01*
X70213Y-129500D01*
X68947Y-130333D01*
X68377Y-130917D01*
X67997Y-131750D01*
X67870Y-132500D01*
X70530D01*
G01X72907Y-131500D02*
X73287Y-132083D01*
X73793Y-132417D01*
X74363Y-132500D01*
X74870Y-132417D01*
X75377Y-132000D01*
X75693Y-131500D01*
X75757Y-131000D01*
X75630Y-130417D01*
X75187Y-130000D01*
X74743Y-129833D01*
X74173D01*
G01X74743D02*
X75123Y-129583D01*
X75440Y-129167D01*
X75567Y-128667D01*
X75440Y-128167D01*
X75123Y-127750D01*
X74553Y-127500D01*
X73983Y-127583D01*
X73413Y-127917D01*
G01X80160Y-132500D02*
Y-127500D01*
X77817Y-131083D01*
X80983D01*
G01X83107Y-131750D02*
X83487Y-132167D01*
X83930Y-132417D01*
X84500Y-132500D01*
X85070Y-132333D01*
X85513Y-132000D01*
X85830Y-131417D01*
X85893Y-130750D01*
X85767Y-130083D01*
X85450Y-129667D01*
X85007Y-129333D01*
X84563Y-129250D01*
X84120Y-129333D01*
X83550Y-129667D01*
X83740Y-127500D01*
X85450D01*
G01X93497Y-132500D02*
Y-127500D01*
X95903D01*
G01X95017Y-129917D02*
X93497D01*
G01X98217Y-132500D02*
X99800Y-127500D01*
X101383Y-132500D01*
G01X100813Y-130750D02*
X98787D01*
G01X103570Y-132500D02*
X106230Y-127500D01*
G01X103570D02*
X106230Y-132500D01*
G01X110000Y-132667D02*
X109873Y-132583D01*
Y-132417D01*
X110000Y-132333D01*
X110127Y-132417D01*
Y-132583D01*
X110000Y-132667D01*
G01Y-130417D02*
X109873Y-130333D01*
Y-130167D01*
X110000Y-130083D01*
X110127Y-130167D01*
Y-130333D01*
X110000Y-130417D01*
G01X114783Y-134167D02*
X114150Y-133333D01*
X113833Y-132500D01*
Y-129167D01*
X114150Y-128333D01*
X114783Y-127500D01*
G01X120200D02*
X119693Y-127667D01*
X119313Y-128083D01*
X119060Y-128583D01*
X118870Y-129250D01*
X118807Y-130000D01*
X118870Y-130750D01*
X119060Y-131417D01*
X119313Y-131917D01*
X119693Y-132333D01*
X120200Y-132500D01*
X120707Y-132333D01*
X121087Y-131917D01*
X121340Y-131417D01*
X121530Y-130750D01*
X121593Y-130000D01*
X121530Y-129250D01*
X121340Y-128583D01*
X121087Y-128083D01*
X120707Y-127667D01*
X120200Y-127500D01*
G01X123907Y-131500D02*
X124287Y-132083D01*
X124793Y-132417D01*
X125363Y-132500D01*
X125870Y-132417D01*
X126377Y-132000D01*
X126693Y-131500D01*
X126757Y-131000D01*
X126630Y-130417D01*
X126187Y-130000D01*
X125743Y-129833D01*
X125173D01*
G01X125743D02*
X126123Y-129583D01*
X126440Y-129167D01*
X126567Y-128667D01*
X126440Y-128167D01*
X126123Y-127750D01*
X125553Y-127500D01*
X124983Y-127583D01*
X124413Y-127917D01*
G01X130717Y-134167D02*
X131350Y-133333D01*
X131667Y-132500D01*
Y-129167D01*
X131350Y-128333D01*
X130717Y-127500D01*
G01X134107Y-131500D02*
X134487Y-132083D01*
X134993Y-132417D01*
X135563Y-132500D01*
X136070Y-132417D01*
X136577Y-132000D01*
X136893Y-131500D01*
X136957Y-131000D01*
X136830Y-130417D01*
X136387Y-130000D01*
X135943Y-129833D01*
X135373D01*
G01X135943D02*
X136323Y-129583D01*
X136640Y-129167D01*
X136767Y-128667D01*
X136640Y-128167D01*
X136323Y-127750D01*
X135753Y-127500D01*
X135183Y-127583D01*
X134613Y-127917D01*
G01X139523Y-131917D02*
X139967Y-132333D01*
X140473Y-132500D01*
X140980Y-132333D01*
X141423Y-131833D01*
X141740Y-131083D01*
X141867Y-130333D01*
Y-129417D01*
X141740Y-128667D01*
X141423Y-128000D01*
X141043Y-127667D01*
X140600Y-127500D01*
X140093Y-127667D01*
X139713Y-128000D01*
X139460Y-128500D01*
X139333Y-129167D01*
X139460Y-129750D01*
X139777Y-130333D01*
X140157Y-130667D01*
X140600Y-130750D01*
X141107Y-130583D01*
X141487Y-130167D01*
X141867Y-129417D01*
G01X145573Y-132500D02*
X145700Y-131417D01*
X145890Y-130500D01*
X146143Y-129667D01*
X146460Y-128750D01*
X146967Y-127500D01*
X144433D01*
G01X149977Y-130833D02*
X151623D01*
G01X154507Y-131500D02*
X154887Y-132083D01*
X155393Y-132417D01*
X155963Y-132500D01*
X156470Y-132417D01*
X156977Y-132000D01*
X157293Y-131500D01*
X157357Y-131000D01*
X157230Y-130417D01*
X156787Y-130000D01*
X156343Y-129833D01*
X155773D01*
G01X156343D02*
X156723Y-129583D01*
X157040Y-129167D01*
X157167Y-128667D01*
X157040Y-128167D01*
X156723Y-127750D01*
X156153Y-127500D01*
X155583Y-127583D01*
X155013Y-127917D01*
G01X159797Y-130417D02*
X160240Y-129833D01*
X160620Y-129500D01*
X161127Y-129333D01*
X161570Y-129500D01*
X161887Y-129833D01*
X162140Y-130333D01*
X162203Y-130917D01*
X162140Y-131417D01*
X161887Y-131917D01*
X161507Y-132333D01*
X161063Y-132500D01*
X160557Y-132333D01*
X160113Y-131833D01*
X159860Y-131083D01*
X159797Y-130250D01*
X159923Y-129167D01*
X160113Y-128583D01*
X160430Y-128000D01*
X160873Y-127583D01*
X161317Y-127500D01*
X161760Y-127667D01*
X162077Y-128083D01*
G01X166100Y-132500D02*
Y-127500D01*
X165340Y-128500D01*
G01Y-132500D02*
X166860D01*
G01X171960D02*
Y-127500D01*
X169617Y-131083D01*
X172783D01*
G01X191000Y-62500D02*
Y-137500D01*
G01Y-112500D02*
X294000D01*
Y-87500D01*
G01X191000D02*
X294000D01*
G01X301507Y-122500D02*
Y-117500D01*
X302773D01*
X303280Y-117750D01*
X303660Y-118083D01*
X303977Y-118583D01*
X304230Y-119167D01*
X304293Y-120000D01*
X304230Y-120833D01*
X303977Y-121417D01*
X303660Y-121917D01*
X303280Y-122250D01*
X302773Y-122500D01*
X301507D01*
G01X306417D02*
X308000Y-117500D01*
X309583Y-122500D01*
G01X309013Y-120750D02*
X306987D01*
G01X313100Y-117500D02*
Y-122500D01*
G01X311643Y-117500D02*
X314557D01*
G01X319467Y-122500D02*
X316933D01*
Y-117500D01*
X319467D01*
G01X318453Y-119917D02*
X316933D01*
G01X323300Y-122667D02*
X323173Y-122583D01*
Y-122417D01*
X323300Y-122333D01*
X323427Y-122417D01*
Y-122583D01*
X323300Y-122667D01*
G01Y-120417D02*
X323173Y-120333D01*
Y-120167D01*
X323300Y-120083D01*
X323427Y-120167D01*
Y-120333D01*
X323300Y-120417D01*
G01X296000Y-62500D02*
Y-137500D01*
G01X294000Y-62500D02*
Y-137500D01*
G01X301633Y-97500D02*
Y-92500D01*
X303153D01*
X303660Y-92750D01*
X304040Y-93333D01*
X304167Y-94000D01*
X304040Y-94667D01*
X303723Y-95167D01*
X303153Y-95417D01*
X301633D01*
G01X306860Y-97667D02*
X309140Y-92500D01*
G01X311643Y-97500D02*
Y-92500D01*
X314557Y-97500D01*
Y-92500D01*
G01X318200Y-97667D02*
X318073Y-97583D01*
Y-97417D01*
X318200Y-97333D01*
X318327Y-97417D01*
Y-97583D01*
X318200Y-97667D01*
G01Y-95417D02*
X318073Y-95333D01*
Y-95167D01*
X318200Y-95083D01*
X318327Y-95167D01*
Y-95333D01*
X318200Y-95417D01*
G01X296000Y-112500D02*
X496000D01*
G01X301633Y-72500D02*
Y-67500D01*
X303153D01*
X303660Y-67750D01*
X304040Y-68333D01*
X304167Y-69000D01*
X304040Y-69667D01*
X303723Y-70167D01*
X303153Y-70417D01*
X301633D01*
G01X306733Y-72500D02*
Y-67500D01*
X308317D01*
X308823Y-67750D01*
X309140Y-68083D01*
X309267Y-68750D01*
X309140Y-69417D01*
X308760Y-69833D01*
X308317Y-70083D01*
X306733D01*
G01X308317D02*
X309267Y-72500D01*
G01X313100D02*
X312593Y-72417D01*
X312150Y-72083D01*
X311770Y-71583D01*
X311517Y-71000D01*
X311390Y-70333D01*
Y-69667D01*
X311517Y-69000D01*
X311770Y-68417D01*
X312150Y-67917D01*
X312593Y-67583D01*
X313100Y-67500D01*
X313607Y-67583D01*
X314050Y-67917D01*
X314430Y-68417D01*
X314683Y-69000D01*
X314810Y-69667D01*
Y-70333D01*
X314683Y-71000D01*
X314430Y-71583D01*
X314050Y-72083D01*
X313607Y-72417D01*
X313100Y-72500D01*
G01X316933Y-71500D02*
X317250Y-72000D01*
X317630Y-72333D01*
X318073Y-72500D01*
X318580Y-72333D01*
X318960Y-72000D01*
X319340Y-71500D01*
X319467Y-70833D01*
Y-67500D01*
G01X324567Y-72500D02*
X322033D01*
Y-67500D01*
X324567D01*
G01X323553Y-69917D02*
X322033D01*
G01X329793Y-67917D02*
X329413Y-67667D01*
X328970Y-67500D01*
X328463D01*
X327893Y-67750D01*
X327450Y-68167D01*
X327133Y-68667D01*
X326880Y-69500D01*
X326817Y-70250D01*
X326943Y-71000D01*
X327133Y-71500D01*
X327513Y-72000D01*
X327957Y-72333D01*
X328400Y-72500D01*
X328843D01*
X329287Y-72333D01*
X329667Y-72083D01*
X329983Y-71750D01*
G01X333500Y-67500D02*
Y-72500D01*
G01X332043Y-67500D02*
X334957D01*
G01X338600Y-72667D02*
X338473Y-72583D01*
Y-72417D01*
X338600Y-72333D01*
X338727Y-72417D01*
Y-72583D01*
X338600Y-72667D01*
G01Y-70417D02*
X338473Y-70333D01*
Y-70167D01*
X338600Y-70083D01*
X338727Y-70167D01*
Y-70333D01*
X338600Y-70417D01*
G01X296000Y-87500D02*
X496000D01*
G01X411000Y-112500D02*
Y-137500D01*
G01X416633Y-122500D02*
Y-117500D01*
X418217D01*
X418723Y-117750D01*
X419040Y-118083D01*
X419167Y-118750D01*
X419040Y-119417D01*
X418660Y-119833D01*
X418217Y-120083D01*
X416633D01*
G01X418217D02*
X419167Y-122500D01*
G01X424267D02*
X421733D01*
Y-117500D01*
X424267D01*
G01X423253Y-119917D02*
X421733D01*
G01X426517Y-117500D02*
X428100Y-122500D01*
X429683Y-117500D01*
G01X433200Y-122667D02*
X433073Y-122583D01*
Y-122417D01*
X433200Y-122333D01*
X433327Y-122417D01*
Y-122583D01*
X433200Y-122667D01*
G01Y-120417D02*
X433073Y-120333D01*
Y-120167D01*
X433200Y-120083D01*
X433327Y-120167D01*
Y-120333D01*
X433200Y-120417D01*
G01X460000Y-112500D02*
Y-137500D01*
G01X-723776Y2987387D02*
Y-376795D01*
Y-489221D01*
X1782976D01*
Y-376795D01*
Y2987387D01*
X-723776D01*
G01X6705Y-124160D02*
X7332Y-124685D01*
X8037Y-125000D01*
X8663D01*
X9290Y-124685D01*
X9760Y-124160D01*
X9995Y-123425D01*
X9838Y-122690D01*
X9447Y-122060D01*
X8742Y-121640D01*
X7802Y-121430D01*
X7253Y-121010D01*
X7018Y-120275D01*
X7175Y-119540D01*
X7567Y-119015D01*
X8115Y-118700D01*
X8663D01*
X9212Y-118910D01*
X9682Y-119435D01*
G01X13005Y-125000D02*
Y-118700D01*
G01X16295D02*
Y-125000D01*
G01Y-121850D02*
X13005D01*
G01X20010Y-118700D02*
X21890D01*
G01X20950D02*
Y-125000D01*
G01X20010D02*
X21890D01*
G01X28817D02*
X25683D01*
Y-118700D01*
X28817D01*
G01X27563Y-121745D02*
X25683D01*
G01X31748Y-125000D02*
Y-118700D01*
X35352Y-125000D01*
Y-118700D01*
G01X39693Y-126155D02*
X40007Y-124790D01*
G01X46150Y-118700D02*
Y-125000D01*
G01X44348Y-118700D02*
X47952D01*
G01X50492Y-125000D02*
X52450Y-118700D01*
X54408Y-125000D01*
G01X53703Y-122795D02*
X51197D01*
G01X57810Y-118700D02*
X59690D01*
G01X58750D02*
Y-125000D01*
G01X57810D02*
X59690D01*
G01X62700Y-118700D02*
X63797Y-125000D01*
X65050Y-118700D01*
X66303Y-125000D01*
X67400Y-118700D01*
G01X69392Y-125000D02*
X71350Y-118700D01*
X73308Y-125000D01*
G01X72603Y-122795D02*
X70097D01*
G01X75848Y-125000D02*
Y-118700D01*
X79452Y-125000D01*
Y-118700D01*
G01X88683Y-125000D02*
Y-118700D01*
X90642D01*
X91268Y-119015D01*
X91660Y-119435D01*
X91817Y-120275D01*
X91660Y-121115D01*
X91190Y-121640D01*
X90642Y-121955D01*
X88683D01*
G01X90642D02*
X91817Y-125000D01*
G01X96550Y-125210D02*
X96393Y-125105D01*
Y-124895D01*
X96550Y-124790D01*
X96707Y-124895D01*
Y-125105D01*
X96550Y-125210D01*
G01X102850Y-125000D02*
X102223Y-124895D01*
X101675Y-124475D01*
X101205Y-123845D01*
X100892Y-123110D01*
X100735Y-122270D01*
Y-121430D01*
X100892Y-120590D01*
X101205Y-119855D01*
X101675Y-119225D01*
X102223Y-118805D01*
X102850Y-118700D01*
X103477Y-118805D01*
X104025Y-119225D01*
X104495Y-119855D01*
X104808Y-120590D01*
X104965Y-121430D01*
Y-122270D01*
X104808Y-123110D01*
X104495Y-123845D01*
X104025Y-124475D01*
X103477Y-124895D01*
X102850Y-125000D01*
G01X109150Y-125210D02*
X108993Y-125105D01*
Y-124895D01*
X109150Y-124790D01*
X109307Y-124895D01*
Y-125105D01*
X109150Y-125210D01*
G01X117173Y-119225D02*
X116703Y-118910D01*
X116155Y-118700D01*
X115528D01*
X114823Y-119015D01*
X114275Y-119540D01*
X113883Y-120170D01*
X113570Y-121220D01*
X113492Y-122165D01*
X113648Y-123110D01*
X113883Y-123740D01*
X114353Y-124370D01*
X114902Y-124790D01*
X115450Y-125000D01*
X115998D01*
X116547Y-124790D01*
X117017Y-124475D01*
X117408Y-124055D01*
G01X121750Y-125210D02*
X121593Y-125105D01*
Y-124895D01*
X121750Y-124790D01*
X121907Y-124895D01*
Y-125105D01*
X121750Y-125210D01*
G01X6627Y-115000D02*
Y-108700D01*
G01X9603D02*
X6627Y-112585D01*
G01X10073Y-115000D02*
X7958Y-110800D01*
G01X12927Y-108700D02*
Y-113215D01*
X13240Y-114160D01*
X13867Y-114790D01*
X14650Y-115000D01*
X15433Y-114790D01*
X16060Y-114160D01*
X16373Y-113215D01*
Y-108700D01*
G01X22517Y-115000D02*
X19383D01*
Y-108700D01*
X22517D01*
G01X21263Y-111745D02*
X19383D01*
G01X26310Y-108700D02*
X28190D01*
G01X27250D02*
Y-115000D01*
G01X26310D02*
X28190D01*
G01X38205Y-114160D02*
X38832Y-114685D01*
X39537Y-115000D01*
X40163D01*
X40790Y-114685D01*
X41260Y-114160D01*
X41495Y-113425D01*
X41338Y-112690D01*
X40947Y-112060D01*
X40242Y-111640D01*
X39302Y-111430D01*
X38753Y-111010D01*
X38518Y-110275D01*
X38675Y-109540D01*
X39067Y-109015D01*
X39615Y-108700D01*
X40163D01*
X40712Y-108910D01*
X41182Y-109435D01*
G01X44505Y-115000D02*
Y-108700D01*
G01X47795D02*
Y-115000D01*
G01Y-111850D02*
X44505D01*
G01X50492Y-115000D02*
X52450Y-108700D01*
X54408Y-115000D01*
G01X53703Y-112795D02*
X51197D01*
G01X56948Y-115000D02*
Y-108700D01*
X60552Y-115000D01*
Y-108700D01*
G01X69705Y-115000D02*
Y-108700D01*
G01X72995D02*
Y-115000D01*
G01Y-111850D02*
X69705D01*
G01X76005Y-114160D02*
X76632Y-114685D01*
X77337Y-115000D01*
X77963D01*
X78590Y-114685D01*
X79060Y-114160D01*
X79295Y-113425D01*
X79138Y-112690D01*
X78747Y-112060D01*
X78042Y-111640D01*
X77102Y-111430D01*
X76553Y-111010D01*
X76318Y-110275D01*
X76475Y-109540D01*
X76867Y-109015D01*
X77415Y-108700D01*
X77963D01*
X78512Y-108910D01*
X78982Y-109435D01*
G01X83010Y-108700D02*
X84890D01*
G01X83950D02*
Y-115000D01*
G01X83010D02*
X84890D01*
G01X88292D02*
X90250Y-108700D01*
X92208Y-115000D01*
G01X91503Y-112795D02*
X88997D01*
G01X94748Y-115000D02*
Y-108700D01*
X98352Y-115000D01*
Y-108700D01*
G01X103320Y-111850D02*
X104887D01*
Y-113740D01*
X104417Y-114370D01*
X103868Y-114790D01*
X103085Y-115000D01*
X102302Y-114790D01*
X101753Y-114370D01*
X101283Y-113740D01*
X100970Y-113005D01*
X100813Y-112165D01*
Y-111430D01*
X100970Y-110800D01*
X101283Y-110065D01*
X101753Y-109435D01*
X102223Y-109015D01*
X102850Y-108700D01*
X103398D01*
X104025Y-108910D01*
X104495Y-109330D01*
G01X108993Y-116155D02*
X109307Y-114790D01*
G01X115450Y-108700D02*
Y-115000D01*
G01X113648Y-108700D02*
X117252D01*
G01X119792Y-115000D02*
X121750Y-108700D01*
X123708Y-115000D01*
G01X123003Y-112795D02*
X120497D01*
G01X128050Y-115000D02*
X127423Y-114895D01*
X126875Y-114475D01*
X126405Y-113845D01*
X126092Y-113110D01*
X125935Y-112270D01*
Y-111430D01*
X126092Y-110590D01*
X126405Y-109855D01*
X126875Y-109225D01*
X127423Y-108805D01*
X128050Y-108700D01*
X128677Y-108805D01*
X129225Y-109225D01*
X129695Y-109855D01*
X130008Y-110590D01*
X130165Y-111430D01*
Y-112270D01*
X130008Y-113110D01*
X129695Y-113845D01*
X129225Y-114475D01*
X128677Y-114895D01*
X128050Y-115000D01*
G01X140650D02*
Y-112165D01*
X139083Y-108700D01*
G01X142217D02*
X140650Y-112165D01*
G01X145227Y-108700D02*
Y-113215D01*
X145540Y-114160D01*
X146167Y-114790D01*
X146950Y-115000D01*
X147733Y-114790D01*
X148360Y-114160D01*
X148673Y-113215D01*
Y-108700D01*
G01X151292Y-115000D02*
X153250Y-108700D01*
X155208Y-115000D01*
G01X154503Y-112795D02*
X151997D01*
G01X157748Y-115000D02*
Y-108700D01*
X161352Y-115000D01*
Y-108700D01*
G01X30650Y-92300D02*
X28130Y-91883D01*
X25925Y-90217D01*
X24035Y-87717D01*
X22775Y-84800D01*
X22145Y-81467D01*
Y-78133D01*
X22775Y-74800D01*
X24035Y-71883D01*
X25925Y-69384D01*
X28130Y-67717D01*
X30650Y-67300D01*
X33170Y-67717D01*
X35375Y-69384D01*
X37265Y-71883D01*
X38525Y-74800D01*
X39155Y-78133D01*
Y-81467D01*
X38525Y-84800D01*
X37265Y-87717D01*
X35375Y-90217D01*
X33170Y-91883D01*
X30650Y-92300D01*
G01X33170Y-85633D02*
X36950Y-92300D01*
G01X50495Y-75634D02*
Y-87300D01*
X51755Y-90217D01*
X53645Y-91883D01*
X55850Y-92300D01*
X58055Y-91883D01*
X59945Y-90217D01*
X61205Y-87300D01*
G01Y-92300D02*
Y-75634D01*
G01X86720Y-92300D02*
Y-75634D01*
G01Y-78550D02*
X85460Y-76884D01*
X83570Y-76050D01*
X81365Y-75634D01*
X79160Y-76467D01*
X77270Y-78133D01*
X76010Y-80634D01*
X75380Y-83967D01*
X76010Y-87300D01*
X77270Y-89801D01*
X79160Y-91467D01*
X81365Y-92300D01*
X83570Y-91883D01*
X85460Y-90634D01*
X86720Y-88967D01*
G01X100895Y-92300D02*
Y-75634D01*
G01Y-79800D02*
X102155Y-77717D01*
X104045Y-76050D01*
X106565Y-75634D01*
X108770Y-76050D01*
X110660Y-77717D01*
X111605Y-80634D01*
Y-92300D01*
G01X131450Y-67300D02*
Y-92300D01*
G01X127040Y-75634D02*
X135860D01*
G01X162320Y-92300D02*
Y-75634D01*
G01Y-78550D02*
X161060Y-76884D01*
X159170Y-76050D01*
X156965Y-75634D01*
X154760Y-76467D01*
X152870Y-78133D01*
X151610Y-80634D01*
X150980Y-83967D01*
X151610Y-87300D01*
X152870Y-89801D01*
X154760Y-91467D01*
X156965Y-92300D01*
X159170Y-91883D01*
X161060Y-90634D01*
X162320Y-88967D01*
G01X6548Y-105000D02*
Y-98700D01*
X10152Y-105000D01*
Y-98700D01*
G01X14650Y-105000D02*
X14023Y-104895D01*
X13475Y-104475D01*
X13005Y-103845D01*
X12692Y-103110D01*
X12535Y-102270D01*
Y-101430D01*
X12692Y-100590D01*
X13005Y-99855D01*
X13475Y-99225D01*
X14023Y-98805D01*
X14650Y-98700D01*
X15277Y-98805D01*
X15825Y-99225D01*
X16295Y-99855D01*
X16608Y-100590D01*
X16765Y-101430D01*
Y-102270D01*
X16608Y-103110D01*
X16295Y-103845D01*
X15825Y-104475D01*
X15277Y-104895D01*
X14650Y-105000D01*
G01X20950Y-105210D02*
X20793Y-105105D01*
Y-104895D01*
X20950Y-104790D01*
X21107Y-104895D01*
Y-105105D01*
X20950Y-105210D01*
G01X27250Y-105000D02*
Y-98700D01*
X26310Y-99960D01*
G01Y-105000D02*
X28190D01*
G01X33550D02*
X34098Y-104895D01*
X34725Y-104580D01*
X35117Y-104055D01*
X35273Y-103320D01*
X35117Y-102585D01*
X34647Y-101955D01*
X33942Y-101640D01*
X33158D01*
X32688Y-101430D01*
X32297Y-100905D01*
X32140Y-100170D01*
X32375Y-99435D01*
X32923Y-98910D01*
X33550Y-98700D01*
X34177Y-98910D01*
X34725Y-99435D01*
X34960Y-100170D01*
X34803Y-100905D01*
X34412Y-101430D01*
X33942Y-101640D01*
X33158D01*
X32453Y-101955D01*
X31983Y-102585D01*
X31827Y-103320D01*
X31983Y-104055D01*
X32375Y-104580D01*
X33002Y-104895D01*
X33550Y-105000D01*
G01X39850D02*
X40398Y-104895D01*
X41025Y-104580D01*
X41417Y-104055D01*
X41573Y-103320D01*
X41417Y-102585D01*
X40947Y-101955D01*
X40242Y-101640D01*
X39458D01*
X38988Y-101430D01*
X38597Y-100905D01*
X38440Y-100170D01*
X38675Y-99435D01*
X39223Y-98910D01*
X39850Y-98700D01*
X40477Y-98910D01*
X41025Y-99435D01*
X41260Y-100170D01*
X41103Y-100905D01*
X40712Y-101430D01*
X40242Y-101640D01*
X39458D01*
X38753Y-101955D01*
X38283Y-102585D01*
X38127Y-103320D01*
X38283Y-104055D01*
X38675Y-104580D01*
X39302Y-104895D01*
X39850Y-105000D01*
G01X45993Y-106155D02*
X46307Y-104790D01*
G01X50100Y-98700D02*
X51197Y-105000D01*
X52450Y-98700D01*
X53703Y-105000D01*
X54800Y-98700D01*
G01X60317Y-105000D02*
X57183D01*
Y-98700D01*
X60317D01*
G01X59063Y-101745D02*
X57183D01*
G01X63248Y-105000D02*
Y-98700D01*
X66852Y-105000D01*
Y-98700D01*
G01X76005Y-105000D02*
Y-98700D01*
G01X79295D02*
Y-105000D01*
G01Y-101850D02*
X76005D01*
G01X81600Y-98700D02*
X82697Y-105000D01*
X83950Y-98700D01*
X85203Y-105000D01*
X86300Y-98700D01*
G01X88292Y-105000D02*
X90250Y-98700D01*
X92208Y-105000D01*
G01X91503Y-102795D02*
X88997D01*
G01X101362Y-99750D02*
X101832Y-99120D01*
X102380Y-98805D01*
X103007Y-98700D01*
X103790Y-98910D01*
X104338Y-99435D01*
X104495Y-100065D01*
X104417Y-100695D01*
X104103Y-101220D01*
X102537Y-102270D01*
X101832Y-103005D01*
X101362Y-104055D01*
X101205Y-105000D01*
X104495D01*
G01X107348D02*
Y-98700D01*
X110952Y-105000D01*
Y-98700D01*
G01X113727Y-105000D02*
Y-98700D01*
X115293D01*
X115920Y-99015D01*
X116390Y-99435D01*
X116782Y-100065D01*
X117095Y-100800D01*
X117173Y-101850D01*
X117095Y-102900D01*
X116782Y-103635D01*
X116390Y-104265D01*
X115920Y-104685D01*
X115293Y-105000D01*
X113727D01*
G01X126483D02*
Y-98700D01*
X128442D01*
X129068Y-99015D01*
X129460Y-99435D01*
X129617Y-100275D01*
X129460Y-101115D01*
X128990Y-101640D01*
X128442Y-101955D01*
X126483D01*
G01X128442D02*
X129617Y-105000D01*
G01X132627D02*
Y-98700D01*
X134193D01*
X134820Y-99015D01*
X135290Y-99435D01*
X135682Y-100065D01*
X135995Y-100800D01*
X136073Y-101850D01*
X135995Y-102900D01*
X135682Y-103635D01*
X135290Y-104265D01*
X134820Y-104685D01*
X134193Y-105000D01*
X132627D01*
G01X140650Y-105210D02*
X140493Y-105105D01*
Y-104895D01*
X140650Y-104790D01*
X140807Y-104895D01*
Y-105105D01*
X140650Y-105210D01*
G01X202000Y-72000D02*
Y-80000D01*
X206000D01*
G01X213800D02*
Y-74667D01*
G01Y-75600D02*
X213400Y-75067D01*
X212800Y-74800D01*
X212100Y-74667D01*
X211400Y-74933D01*
X210800Y-75467D01*
X210400Y-76267D01*
X210200Y-77333D01*
X210400Y-78400D01*
X210800Y-79200D01*
X211400Y-79733D01*
X212100Y-80000D01*
X212800Y-79867D01*
X213400Y-79467D01*
X213800Y-78934D01*
G01X217900Y-82400D02*
X218500Y-82667D01*
X219300Y-82400D01*
X219800Y-81867D01*
X220200Y-81200D01*
X220800Y-79067D01*
X222100Y-74667D01*
G01X218900D02*
X220800Y-79067D01*
G01X226500Y-76400D02*
X229700D01*
X229400Y-75467D01*
X228900Y-74933D01*
X228200Y-74667D01*
X227500Y-74800D01*
X226900Y-75200D01*
X226500Y-76133D01*
X226300Y-76934D01*
Y-77733D01*
X226500Y-78533D01*
X227000Y-79333D01*
X227600Y-79867D01*
X228300Y-80000D01*
X229000Y-79733D01*
X229700Y-78934D01*
G01X234600Y-80000D02*
Y-74667D01*
G01Y-75733D02*
X235100Y-75200D01*
X235600Y-74800D01*
X236300Y-74667D01*
X236800Y-74800D01*
X237400Y-75200D01*
G01X223400Y-128934D02*
X224200Y-129600D01*
X225100Y-130000D01*
X225900D01*
X226700Y-129600D01*
X227300Y-128934D01*
X227600Y-128000D01*
X227400Y-127067D01*
X226900Y-126267D01*
X226000Y-125733D01*
X224800Y-125467D01*
X224100Y-124933D01*
X223800Y-124000D01*
X224000Y-123067D01*
X224500Y-122400D01*
X225200Y-122000D01*
X225900D01*
X226600Y-122267D01*
X227200Y-122933D01*
G01X235300Y-130000D02*
Y-124667D01*
G01Y-125600D02*
X234900Y-125067D01*
X234300Y-124800D01*
X233600Y-124667D01*
X232900Y-124933D01*
X232300Y-125467D01*
X231900Y-126267D01*
X231700Y-127333D01*
X231900Y-128400D01*
X232300Y-129200D01*
X232900Y-129733D01*
X233600Y-130000D01*
X234300Y-129867D01*
X234900Y-129467D01*
X235300Y-128934D01*
G01X239800Y-130000D02*
Y-124667D01*
G01Y-126000D02*
X240200Y-125333D01*
X240800Y-124800D01*
X241600Y-124667D01*
X242300Y-124800D01*
X242900Y-125333D01*
X243200Y-126267D01*
Y-130000D01*
G01X251300Y-122000D02*
Y-130000D01*
G01Y-128800D02*
X250900Y-129467D01*
X250300Y-129867D01*
X249600Y-130000D01*
X248800Y-129733D01*
X248200Y-129067D01*
X247800Y-128267D01*
X247700Y-127333D01*
X247800Y-126400D01*
X248200Y-125600D01*
X248800Y-124933D01*
X249600Y-124667D01*
X250300Y-124800D01*
X250800Y-125067D01*
X251300Y-125600D01*
G01X255400Y-132400D02*
X256000Y-132667D01*
X256800Y-132400D01*
X257300Y-131867D01*
X257700Y-131200D01*
X258300Y-129067D01*
X259600Y-124667D01*
G01X256400D02*
X258300Y-129067D01*
G01X234300Y-97000D02*
X236700D01*
G01X235500D02*
Y-105000D01*
G01X234300D02*
X236700D01*
G01X241200D02*
Y-97000D01*
X245800Y-105000D01*
Y-97000D01*
G01X249600Y-98333D02*
X250200Y-97533D01*
X250900Y-97133D01*
X251700Y-97000D01*
X252700Y-97267D01*
X253400Y-97933D01*
X253600Y-98733D01*
X253500Y-99534D01*
X253100Y-100200D01*
X251100Y-101533D01*
X250200Y-102467D01*
X249600Y-103800D01*
X249400Y-105000D01*
X253600D01*
G01Y-76667D02*
X254300Y-75733D01*
X254900Y-75200D01*
X255700Y-74933D01*
X256400Y-75200D01*
X256900Y-75733D01*
X257300Y-76533D01*
X257400Y-77467D01*
X257300Y-78267D01*
X256900Y-79067D01*
X256300Y-79733D01*
X255600Y-80000D01*
X254800Y-79733D01*
X254100Y-78934D01*
X253700Y-77733D01*
X253600Y-76400D01*
X253800Y-74667D01*
X254100Y-73733D01*
X254600Y-72800D01*
X255300Y-72133D01*
X256000Y-72000D01*
X256700Y-72267D01*
X257200Y-72933D01*
G01X328600Y-123333D02*
X329200Y-122533D01*
X329900Y-122133D01*
X330700Y-122000D01*
X331700Y-122267D01*
X332400Y-122933D01*
X332600Y-123733D01*
X332500Y-124534D01*
X332100Y-125200D01*
X330100Y-126533D01*
X329200Y-127467D01*
X328600Y-128800D01*
X328400Y-130000D01*
X332600D01*
G01X338500Y-122000D02*
X337700Y-122267D01*
X337100Y-122933D01*
X336700Y-123733D01*
X336400Y-124800D01*
X336300Y-126000D01*
X336400Y-127200D01*
X336700Y-128267D01*
X337100Y-129067D01*
X337700Y-129733D01*
X338500Y-130000D01*
X339300Y-129733D01*
X339900Y-129067D01*
X340300Y-128267D01*
X340600Y-127200D01*
X340700Y-126000D01*
X340600Y-124800D01*
X340300Y-123733D01*
X339900Y-122933D01*
X339300Y-122267D01*
X338500Y-122000D01*
G01X346500Y-130000D02*
Y-122000D01*
X345300Y-123600D01*
G01Y-130000D02*
X347700D01*
G01X352600Y-123333D02*
X353200Y-122533D01*
X353900Y-122133D01*
X354700Y-122000D01*
X355700Y-122267D01*
X356400Y-122933D01*
X356600Y-123733D01*
X356500Y-124534D01*
X356100Y-125200D01*
X354100Y-126533D01*
X353200Y-127467D01*
X352600Y-128800D01*
X352400Y-130000D01*
X356600D01*
G01X360700Y-130267D02*
X364300Y-122000D01*
G01X370500D02*
X369700Y-122267D01*
X369100Y-122933D01*
X368700Y-123733D01*
X368400Y-124800D01*
X368300Y-126000D01*
X368400Y-127200D01*
X368700Y-128267D01*
X369100Y-129067D01*
X369700Y-129733D01*
X370500Y-130000D01*
X371300Y-129733D01*
X371900Y-129067D01*
X372300Y-128267D01*
X372600Y-127200D01*
X372700Y-126000D01*
X372600Y-124800D01*
X372300Y-123733D01*
X371900Y-122933D01*
X371300Y-122267D01*
X370500Y-122000D01*
G01X376800Y-129067D02*
X377500Y-129733D01*
X378300Y-130000D01*
X379100Y-129733D01*
X379800Y-128934D01*
X380300Y-127733D01*
X380500Y-126533D01*
Y-125067D01*
X380300Y-123867D01*
X379800Y-122800D01*
X379200Y-122267D01*
X378500Y-122000D01*
X377700Y-122267D01*
X377100Y-122800D01*
X376700Y-123600D01*
X376500Y-124667D01*
X376700Y-125600D01*
X377200Y-126533D01*
X377800Y-127067D01*
X378500Y-127200D01*
X379300Y-126934D01*
X379900Y-126267D01*
X380500Y-125067D01*
G01X384700Y-130267D02*
X388300Y-122000D01*
G01X392600Y-123333D02*
X393200Y-122533D01*
X393900Y-122133D01*
X394700Y-122000D01*
X395700Y-122267D01*
X396400Y-122933D01*
X396600Y-123733D01*
X396500Y-124534D01*
X396100Y-125200D01*
X394100Y-126533D01*
X393200Y-127467D01*
X392600Y-128800D01*
X392400Y-130000D01*
X396600D01*
G01X402500D02*
X403200Y-129867D01*
X404000Y-129467D01*
X404500Y-128800D01*
X404700Y-127867D01*
X404500Y-126934D01*
X403900Y-126133D01*
X403000Y-125733D01*
X402000D01*
X401400Y-125467D01*
X400900Y-124800D01*
X400700Y-123867D01*
X401000Y-122933D01*
X401700Y-122267D01*
X402500Y-122000D01*
X403300Y-122267D01*
X404000Y-122933D01*
X404300Y-123867D01*
X404100Y-124800D01*
X403600Y-125467D01*
X403000Y-125733D01*
X402000D01*
X401100Y-126133D01*
X400500Y-126934D01*
X400300Y-127867D01*
X400500Y-128800D01*
X401000Y-129467D01*
X401800Y-129867D01*
X402500Y-130000D01*
G01X328300Y-105000D02*
Y-97000D01*
X330300D01*
X331100Y-97400D01*
X331700Y-97933D01*
X332200Y-98733D01*
X332600Y-99667D01*
X332700Y-101000D01*
X332600Y-102333D01*
X332200Y-103267D01*
X331700Y-104067D01*
X331100Y-104600D01*
X330300Y-105000D01*
X328300D01*
G01X336000D02*
X338500Y-97000D01*
X341000Y-105000D01*
G01X340100Y-102200D02*
X336900D01*
G01X346500Y-97000D02*
X345700Y-97267D01*
X345100Y-97933D01*
X344700Y-98733D01*
X344400Y-99800D01*
X344300Y-101000D01*
X344400Y-102200D01*
X344700Y-103267D01*
X345100Y-104067D01*
X345700Y-104733D01*
X346500Y-105000D01*
X347300Y-104733D01*
X347900Y-104067D01*
X348300Y-103267D01*
X348600Y-102200D01*
X348700Y-101000D01*
X348600Y-99800D01*
X348300Y-98733D01*
X347900Y-97933D01*
X347300Y-97267D01*
X346500Y-97000D01*
G01X354500D02*
Y-105000D01*
G01X352200Y-97000D02*
X356800D01*
G01X360600Y-101667D02*
X361300Y-100733D01*
X361900Y-100200D01*
X362700Y-99933D01*
X363400Y-100200D01*
X363900Y-100733D01*
X364300Y-101533D01*
X364400Y-102467D01*
X364300Y-103267D01*
X363900Y-104067D01*
X363300Y-104733D01*
X362600Y-105000D01*
X361800Y-104733D01*
X361100Y-103934D01*
X360700Y-102733D01*
X360600Y-101400D01*
X360800Y-99667D01*
X361100Y-98733D01*
X361600Y-97800D01*
X362300Y-97133D01*
X363000Y-97000D01*
X363700Y-97267D01*
X364200Y-97933D01*
G01X367900Y-105000D02*
Y-97000D01*
X370500Y-103667D01*
X373100Y-97000D01*
Y-105000D01*
G01X378500Y-97000D02*
Y-105000D01*
G01X376200Y-97000D02*
X380800D01*
G01X387300Y-100733D02*
X387700Y-100333D01*
X388000Y-99667D01*
X388200Y-98733D01*
X388000Y-97933D01*
X387600Y-97400D01*
X386900Y-97000D01*
X384200D01*
Y-105000D01*
X387500D01*
X388200Y-104467D01*
X388600Y-103667D01*
X388800Y-102733D01*
X388600Y-101800D01*
X388000Y-101000D01*
X387300Y-100733D01*
X384200D01*
G01X394500Y-105000D02*
X395200Y-104867D01*
X396000Y-104467D01*
X396500Y-103800D01*
X396700Y-102867D01*
X396500Y-101934D01*
X395900Y-101133D01*
X395000Y-100733D01*
X394000D01*
X393400Y-100467D01*
X392900Y-99800D01*
X392700Y-98867D01*
X393000Y-97933D01*
X393700Y-97267D01*
X394500Y-97000D01*
X395300Y-97267D01*
X396000Y-97933D01*
X396300Y-98867D01*
X396100Y-99800D01*
X395600Y-100467D01*
X395000Y-100733D01*
X394000D01*
X393100Y-101133D01*
X392500Y-101934D01*
X392300Y-102867D01*
X392500Y-103800D01*
X393000Y-104467D01*
X393800Y-104867D01*
X394500Y-105000D01*
G01X400300D02*
Y-97000D01*
X402300D01*
X403100Y-97400D01*
X403700Y-97933D01*
X404200Y-98733D01*
X404600Y-99667D01*
X404700Y-101000D01*
X404600Y-102333D01*
X404200Y-103267D01*
X403700Y-104067D01*
X403100Y-104600D01*
X402300Y-105000D01*
X400300D01*
G01X410500Y-97000D02*
X409700Y-97267D01*
X409100Y-97933D01*
X408700Y-98733D01*
X408400Y-99800D01*
X408300Y-101000D01*
X408400Y-102200D01*
X408700Y-103267D01*
X409100Y-104067D01*
X409700Y-104733D01*
X410500Y-105000D01*
X411300Y-104733D01*
X411900Y-104067D01*
X412300Y-103267D01*
X412600Y-102200D01*
X412700Y-101000D01*
X412600Y-99800D01*
X412300Y-98733D01*
X411900Y-97933D01*
X411300Y-97267D01*
X410500Y-97000D01*
G01X350500Y-72000D02*
Y-80000D01*
G01X348200Y-72000D02*
X352800D01*
G01X356600Y-76667D02*
X357300Y-75733D01*
X357900Y-75200D01*
X358700Y-74933D01*
X359400Y-75200D01*
X359900Y-75733D01*
X360300Y-76533D01*
X360400Y-77467D01*
X360300Y-78267D01*
X359900Y-79067D01*
X359300Y-79733D01*
X358600Y-80000D01*
X357800Y-79733D01*
X357100Y-78934D01*
X356700Y-77733D01*
X356600Y-76400D01*
X356800Y-74667D01*
X357100Y-73733D01*
X357600Y-72800D01*
X358300Y-72133D01*
X359000Y-72000D01*
X359700Y-72267D01*
X360200Y-72933D01*
G01X363900Y-80000D02*
Y-72000D01*
X366500Y-78667D01*
X369100Y-72000D01*
Y-80000D01*
G01X371500Y-82667D02*
X377500D01*
G01X380500Y-80000D02*
Y-72000D01*
X382900D01*
X383700Y-72400D01*
X384300Y-73333D01*
X384500Y-74400D01*
X384300Y-75467D01*
X383800Y-76267D01*
X382900Y-76667D01*
X380500D01*
G01X388300Y-80000D02*
Y-72000D01*
X390300D01*
X391100Y-72400D01*
X391700Y-72933D01*
X392200Y-73733D01*
X392600Y-74667D01*
X392700Y-76000D01*
X392600Y-77333D01*
X392200Y-78267D01*
X391700Y-79067D01*
X391100Y-79600D01*
X390300Y-80000D01*
X388300D01*
G01X399300Y-75733D02*
X399700Y-75333D01*
X400000Y-74667D01*
X400200Y-73733D01*
X400000Y-72933D01*
X399600Y-72400D01*
X398900Y-72000D01*
X396200D01*
Y-80000D01*
X399500D01*
X400200Y-79467D01*
X400600Y-78667D01*
X400800Y-77733D01*
X400600Y-76800D01*
X400000Y-76000D01*
X399300Y-75733D01*
X396200D01*
G01X403500Y-82667D02*
X409500D01*
G01X412300Y-80000D02*
Y-72000D01*
X414300D01*
X415100Y-72400D01*
X415700Y-72933D01*
X416200Y-73733D01*
X416600Y-74667D01*
X416700Y-76000D01*
X416600Y-77333D01*
X416200Y-78267D01*
X415700Y-79067D01*
X415100Y-79600D01*
X414300Y-80000D01*
X412300D01*
G01X419500Y-82667D02*
X425500D01*
G01X431300Y-75733D02*
X431700Y-75333D01*
X432000Y-74667D01*
X432200Y-73733D01*
X432000Y-72933D01*
X431600Y-72400D01*
X430900Y-72000D01*
X428200D01*
Y-80000D01*
X431500D01*
X432200Y-79467D01*
X432600Y-78667D01*
X432800Y-77733D01*
X432600Y-76800D01*
X432000Y-76000D01*
X431300Y-75733D01*
X428200D01*
G01X436300Y-80000D02*
Y-72000D01*
X438300D01*
X439100Y-72400D01*
X439700Y-72933D01*
X440200Y-73733D01*
X440600Y-74667D01*
X440700Y-76000D01*
X440600Y-77333D01*
X440200Y-78267D01*
X439700Y-79067D01*
X439100Y-79600D01*
X438300Y-80000D01*
X436300D01*
G01X443300Y-130000D02*
Y-122000D01*
X445300D01*
X446100Y-122400D01*
X446700Y-122933D01*
X447200Y-123733D01*
X447600Y-124667D01*
X447700Y-126000D01*
X447600Y-127333D01*
X447200Y-128267D01*
X446700Y-129067D01*
X446100Y-129600D01*
X445300Y-130000D01*
X443300D01*
G01X473000D02*
Y-122000D01*
X471800Y-123600D01*
G01Y-130000D02*
X474200D01*
G01X478800Y-128800D02*
X479400Y-129467D01*
X480100Y-129867D01*
X481000Y-130000D01*
X481900Y-129733D01*
X482600Y-129200D01*
X483100Y-128267D01*
X483200Y-127200D01*
X483000Y-126133D01*
X482500Y-125467D01*
X481800Y-124933D01*
X481100Y-124800D01*
X480400Y-124933D01*
X479500Y-125467D01*
X479800Y-122000D01*
X482500D01*
G54D11*
X22735Y216976D03*
X27735Y206976D03*
X17735D03*
Y233811D03*
X27735D03*
X22735Y243811D03*
Y1957291D03*
X27735Y1947291D03*
X17735D03*
X22735Y2061661D03*
X27735Y2051661D03*
X17735D03*
X37735Y24953D03*
X32735Y34953D03*
X42735Y216976D03*
X32735D03*
X47735Y206976D03*
X37735D03*
Y233811D03*
X47735D03*
X32735Y243811D03*
X42735D03*
X37735Y415834D03*
X42735Y1957291D03*
X32735D03*
X47735Y1947291D03*
X37735D03*
X42735Y2061661D03*
X32735D03*
X47735Y2051661D03*
X37735D03*
X52735Y216976D03*
Y243811D03*
Y1957291D03*
Y2061661D03*
X189762Y73105D03*
X190289Y152050D03*
X190357Y247568D03*
X190817Y331786D03*
X189761Y421732D03*
X190553Y506517D03*
X192888Y598130D03*
X190816Y681645D03*
X191846Y774526D03*
X191606Y856244D03*
X196311Y947202D03*
X195516Y1032544D03*
X191250Y1122856D03*
X191342Y1206233D03*
X191846Y1299104D03*
X190552Y1380966D03*
X189463Y1474162D03*
X191079Y1557277D03*
X192143Y1648177D03*
X191607Y1731351D03*
X191530Y1823227D03*
X190289Y1900420D03*
X192125Y1998730D03*
X191530Y2043388D03*
G54D12*
X5491Y528544D03*
Y1603149D03*
X67499Y528544D03*
Y1603149D03*
G54D13*
X17480Y599901D03*
Y627264D03*
Y1471949D03*
Y1499311D03*
G54D14*
X15547Y723112D03*
X25389D03*
X15547Y746734D03*
X25389D03*
X7673Y734923D03*
X25389Y770357D03*
Y778231D03*
X15547Y801853D03*
X25389Y786105D03*
Y793979D03*
X7673Y797915D03*
Y805790D03*
X15547Y809727D03*
Y817601D03*
Y825475D03*
X25389D03*
X7673Y813664D03*
Y821538D03*
Y853034D03*
X15547Y864845D03*
Y872719D03*
X25389D03*
X7673Y868782D03*
Y876656D03*
X15547Y880593D03*
Y888467D03*
X25389Y896341D03*
X7673Y884530D03*
Y892404D03*
X15547Y904215D03*
X25389D03*
Y912089D03*
X7673Y923900D03*
X15547Y927837D03*
Y935711D03*
Y943585D03*
Y951459D03*
X25389Y943585D03*
Y951459D03*
X7673Y931774D03*
Y939648D03*
Y947522D03*
X25389Y959333D03*
Y967207D03*
X7673Y963270D03*
X15547Y998703D03*
X7673Y1002640D03*
Y1010514D03*
Y1018388D03*
X15547Y1006577D03*
Y1014451D03*
Y1022325D03*
X25389Y1006577D03*
Y1014451D03*
Y1022325D03*
X7673Y1026262D03*
X15547Y1030199D03*
X25389D03*
X25393Y1065629D03*
X7677Y1069566D03*
X15551Y1089251D03*
X25393Y1073503D03*
X7677Y1093188D03*
X15551Y1097125D03*
Y1104999D03*
Y1112873D03*
X25393Y1104999D03*
Y1112873D03*
Y1120748D03*
X7677Y1101062D03*
Y1108936D03*
Y1116810D03*
X15551Y1128622D03*
X25393D03*
X15551Y1152244D03*
Y1160118D03*
Y1167992D03*
X25393Y1152244D03*
Y1167992D03*
X7677Y1148306D03*
Y1156180D03*
Y1164055D03*
X15551Y1175866D03*
X25393D03*
Y1183740D03*
Y1191614D03*
X7677Y1171929D03*
Y1187677D03*
X15551Y1207362D03*
Y1215236D03*
X7677Y1211299D03*
X15551Y1223110D03*
Y1230984D03*
X25393D03*
Y1238858D03*
X7677Y1219173D03*
Y1227047D03*
Y1234921D03*
X15551Y1246732D03*
X25393D03*
Y1262480D03*
X15551Y1286102D03*
X25393Y1270354D03*
Y1286102D03*
X7677Y1266417D03*
Y1282165D03*
X15551Y1293976D03*
Y1301850D03*
Y1309724D03*
X25393Y1293976D03*
Y1301850D03*
Y1309724D03*
X7677Y1290039D03*
Y1297913D03*
Y1305787D03*
Y1313661D03*
X25393Y1317598D03*
X7677Y1360905D03*
X15551Y1356968D03*
X7677Y1376653D03*
X15551Y1364842D03*
X25393Y1372716D03*
X15551Y1388464D03*
X33263Y734923D03*
Y766419D03*
Y774293D03*
Y782167D03*
Y790041D03*
Y853034D03*
Y892404D03*
Y900278D03*
Y908152D03*
Y931774D03*
Y947522D03*
Y955396D03*
Y963270D03*
Y971144D03*
Y1010514D03*
Y1018388D03*
Y1026262D03*
X33267Y1061692D03*
Y1093188D03*
Y1108936D03*
Y1116810D03*
Y1124684D03*
Y1132558D03*
Y1164055D03*
Y1171929D03*
Y1179803D03*
Y1187677D03*
Y1211299D03*
Y1234921D03*
Y1242795D03*
Y1250669D03*
Y1290039D03*
Y1297913D03*
Y1305787D03*
Y1313661D03*
Y1360905D03*
Y1384527D03*
X166500Y126110D03*
Y118626D03*
Y111407D03*
X166329Y140623D03*
X166500Y132705D03*
X166329Y148066D03*
Y156102D03*
Y163621D03*
X156430Y461714D03*
Y483012D03*
X156259Y490930D03*
X156430Y468933D03*
Y476417D03*
X156259Y513928D03*
Y498373D03*
Y506409D03*
X155444Y822725D03*
X162872D03*
Y830209D03*
X155444D03*
X171524Y844722D03*
Y852165D03*
X162872Y836804D03*
X155444D03*
X162701Y844722D03*
X155273D03*
X162701Y852165D03*
X155273D03*
X171524Y860201D03*
Y867720D03*
X162701Y860201D03*
X155273D03*
X162701Y867720D03*
X155273D03*
X169375Y1176256D03*
Y1190335D03*
Y1183740D03*
X153124Y1176256D03*
X160552D03*
Y1183740D03*
Y1190335D03*
X153124D03*
Y1183740D03*
X160552Y1169037D03*
X153124D03*
X169204Y1198253D03*
X160381D03*
X152953D03*
X154109Y1499221D03*
X161537D03*
Y1506440D03*
X170360D03*
X154109D03*
X153938Y1528437D03*
X154109Y1513924D03*
Y1520519D03*
X170360Y1513924D03*
Y1520519D03*
X161537D03*
Y1513924D03*
X161366Y1528437D03*
X170189D03*
X153938Y1535880D03*
Y1543916D03*
Y1551435D03*
X170189Y1535880D03*
Y1543916D03*
X161366Y1535880D03*
Y1543916D03*
Y1551435D03*
X170189D03*
X152091Y1866003D03*
X159519D03*
X152091Y1880706D03*
Y1887301D03*
X168342Y1880706D03*
Y1887301D03*
X159519D03*
Y1880706D03*
Y1873222D03*
X168342D03*
X152091D03*
X151920Y1902662D03*
Y1910698D03*
X168171Y1902662D03*
Y1910698D03*
X159348Y1902662D03*
Y1910698D03*
X151920Y1895219D03*
X159348D03*
X168171D03*
X151920Y1918217D03*
X159348D03*
X168171D03*
X173928Y126110D03*
Y118626D03*
Y111407D03*
X173757Y140623D03*
X173928Y132705D03*
X173757Y148066D03*
Y156102D03*
Y163621D03*
X175033Y261594D03*
Y268813D03*
Y282892D03*
X174862Y290810D03*
Y298253D03*
X175033Y276297D03*
X174862Y313808D03*
Y306289D03*
X179191Y822725D03*
Y830209D03*
X171695Y822725D03*
Y830209D03*
X179191Y836804D03*
X171695D03*
X179020Y844722D03*
Y852165D03*
Y860201D03*
Y867720D03*
X176871Y1176256D03*
Y1190335D03*
Y1183740D03*
X176700Y1198253D03*
X177856Y1506440D03*
Y1513924D03*
Y1520519D03*
X177685Y1528437D03*
Y1535880D03*
Y1543916D03*
Y1551435D03*
X175838Y1880706D03*
Y1887301D03*
Y1873222D03*
X175667Y1902662D03*
Y1910698D03*
Y1895219D03*
Y1918217D03*
X240955Y56999D03*
Y64483D03*
X240784Y78996D03*
X240955Y71078D03*
X240784Y94475D03*
Y101994D03*
Y86439D03*
X236537Y244995D03*
X227714Y237776D03*
Y244995D03*
X244033D03*
X236537Y259074D03*
X236366Y266992D03*
Y274435D03*
X227714Y259074D03*
X227543Y266992D03*
Y274435D03*
X244033Y259074D03*
X243862Y266992D03*
Y274435D03*
X236537Y252479D03*
X227714D03*
X244033D03*
X236366Y289990D03*
X227543D03*
X243862D03*
X236366Y282471D03*
X227543D03*
X243862D03*
X232548Y461083D03*
X241371Y482381D03*
X241200Y490299D03*
X232548Y482381D03*
X232377Y490299D03*
X241371Y468302D03*
Y475786D03*
X232548Y468302D03*
Y475786D03*
X241200Y513297D03*
X232377D03*
X241200Y497742D03*
X232377D03*
X241200Y505778D03*
X232377D03*
X230963Y608108D03*
X238391D03*
X230963Y601513D03*
X238391D03*
Y594029D03*
X230963D03*
X230792Y631505D03*
X238220D03*
X230792Y623469D03*
X238220D03*
X230792Y616026D03*
X238220D03*
X230792Y639024D03*
X238220D03*
X231339Y959673D03*
X238767D03*
Y967157D03*
Y973752D03*
X231339D03*
Y967157D03*
X238767Y952454D03*
X231339D03*
X238596Y981670D03*
X231168D03*
X238596Y997149D03*
Y989113D03*
X231168Y997149D03*
Y989113D03*
X238596Y1004668D03*
X231168D03*
X238659Y1215296D03*
X231231D03*
X238659Y1207777D03*
Y1199741D03*
X231231Y1207777D03*
Y1199741D03*
X225131Y1663167D03*
X241382Y1670386D03*
X232559Y1663167D03*
Y1670386D03*
X225131D03*
X241211Y1699826D03*
X241382Y1677870D03*
X241211Y1692383D03*
X241382Y1684465D03*
X232559D03*
Y1677870D03*
X232388Y1692383D03*
Y1699826D03*
X225131Y1684465D03*
Y1677870D03*
X224960Y1692383D03*
Y1699826D03*
X241211Y1715381D03*
Y1707862D03*
X232388D03*
Y1715381D03*
X224960Y1707862D03*
Y1715381D03*
X248451Y56999D03*
Y64483D03*
X248280Y78996D03*
X248451Y71078D03*
X248280Y94475D03*
Y101994D03*
Y86439D03*
X248867Y482381D03*
X248696Y490299D03*
X248867Y468302D03*
Y475786D03*
X248696Y513297D03*
Y497742D03*
Y505778D03*
X254710Y608108D03*
Y601513D03*
Y594029D03*
X247214Y608108D03*
Y601513D03*
Y594029D03*
X254539Y631505D03*
Y623469D03*
Y616026D03*
X247043Y631505D03*
Y623469D03*
Y616026D03*
X267433Y624321D03*
X254539Y639024D03*
X247043D03*
X255086Y959673D03*
Y973752D03*
Y967157D03*
X247590Y959673D03*
Y973752D03*
Y967157D03*
X254915Y981670D03*
Y997149D03*
Y989113D03*
X247419Y981670D03*
Y997149D03*
Y989113D03*
X254915Y1004668D03*
X247419D03*
X254978Y1215296D03*
X247482D03*
X254978Y1207777D03*
Y1199741D03*
X247482Y1207777D03*
Y1199741D03*
X248878Y1670386D03*
X248707Y1699826D03*
X248878Y1677870D03*
Y1684465D03*
X248707Y1692383D03*
Y1707862D03*
Y1715381D03*
X279044Y624627D03*
X354391Y1329686D03*
Y1350706D03*
Y1360043D03*
Y1340201D03*
Y1376210D03*
Y1367771D03*
X366169Y1329686D03*
Y1350706D03*
Y1360043D03*
Y1340201D03*
Y1376210D03*
Y1367771D03*
G54D15*
X23402Y1685410D03*
Y1701945D03*
Y1735016D03*
Y1751551D03*
Y1784622D03*
Y1801158D03*
G54D16*
X119920Y98071D03*
Y108071D03*
Y118071D03*
Y128071D03*
Y138071D03*
Y148071D03*
Y158071D03*
Y168071D03*
Y178071D03*
Y188071D03*
Y198071D03*
Y208071D03*
Y446102D03*
Y456102D03*
Y466102D03*
Y476102D03*
Y486102D03*
Y496102D03*
Y506102D03*
Y516102D03*
Y526102D03*
Y536102D03*
Y546102D03*
Y556102D03*
Y794134D03*
Y804134D03*
Y814134D03*
Y824134D03*
Y834134D03*
Y844134D03*
Y854134D03*
Y864134D03*
Y874134D03*
Y884134D03*
Y894134D03*
Y904134D03*
Y1142165D03*
Y1152165D03*
Y1162165D03*
Y1172165D03*
Y1182165D03*
Y1192165D03*
Y1202165D03*
Y1212165D03*
Y1222165D03*
Y1232165D03*
Y1242165D03*
Y1252165D03*
Y1490197D03*
Y1500197D03*
Y1510197D03*
Y1520197D03*
Y1530197D03*
Y1540197D03*
Y1550197D03*
Y1560197D03*
Y1570197D03*
Y1580197D03*
Y1590197D03*
Y1600197D03*
Y1838228D03*
Y1848228D03*
Y1858228D03*
Y1868228D03*
Y1878228D03*
Y1888228D03*
Y1898228D03*
Y1908228D03*
Y1918228D03*
Y1928228D03*
Y1938228D03*
Y1948228D03*
X139920Y98071D03*
Y128071D03*
Y118071D03*
Y108071D03*
Y148071D03*
Y138071D03*
Y178071D03*
Y168071D03*
Y158071D03*
Y198071D03*
Y188071D03*
Y208071D03*
Y406102D03*
Y466102D03*
Y456102D03*
Y446102D03*
Y486102D03*
Y476102D03*
Y516102D03*
Y506102D03*
Y496102D03*
Y536102D03*
Y526102D03*
Y556102D03*
Y546102D03*
Y804134D03*
Y794134D03*
Y824134D03*
Y814134D03*
Y854134D03*
Y844134D03*
Y834134D03*
Y874134D03*
Y864134D03*
Y904134D03*
Y894134D03*
Y884134D03*
Y1122165D03*
Y1142165D03*
Y1162165D03*
Y1152165D03*
Y1192165D03*
Y1182165D03*
Y1172165D03*
Y1212165D03*
Y1202165D03*
Y1242165D03*
Y1232165D03*
Y1222165D03*
Y1252165D03*
Y1500197D03*
Y1490197D03*
Y1530197D03*
Y1520197D03*
Y1510197D03*
Y1550197D03*
Y1540197D03*
Y1580197D03*
Y1570197D03*
Y1560197D03*
Y1600197D03*
Y1590197D03*
Y1838228D03*
Y1868228D03*
Y1858228D03*
Y1848228D03*
Y1888228D03*
Y1878228D03*
Y1918228D03*
Y1908228D03*
Y1898228D03*
Y1938228D03*
Y1928228D03*
Y1948228D03*
G54D17*
X173385Y32520D03*
Y21890D03*
X183385Y32520D03*
Y21890D03*
X193385Y32520D03*
Y21890D03*
X173385Y196890D03*
X183385D03*
X193385D03*
X173385Y207520D03*
X183385D03*
X193385D03*
X173385Y371890D03*
X183385D03*
X193385D03*
X173385Y382520D03*
X183385D03*
X193385D03*
X173386Y557520D03*
Y546890D03*
X183386Y557520D03*
Y546890D03*
X193386Y557520D03*
Y546890D03*
X173386Y732520D03*
Y721890D03*
X183386Y732520D03*
Y721890D03*
X193386Y732520D03*
Y721890D03*
X173385Y896890D03*
X183385D03*
X193385D03*
X173385Y907520D03*
X183385D03*
X193385D03*
X173385Y1071890D03*
X183385D03*
X193385D03*
X173385Y1082520D03*
X183385D03*
X193385D03*
X173385Y1257520D03*
Y1246890D03*
X183385Y1257520D03*
Y1246890D03*
X193385Y1257520D03*
Y1246890D03*
X173385Y1432520D03*
Y1421890D03*
X183385Y1432520D03*
Y1421890D03*
X193385Y1432520D03*
Y1421890D03*
X173385Y1596890D03*
X183385D03*
X193385D03*
X173385Y1607520D03*
X183385D03*
X193385D03*
X173385Y1771890D03*
X183385D03*
X193385D03*
X173385Y1782520D03*
X183385D03*
X193385D03*
X173385Y1957520D03*
Y1946890D03*
X183385Y1957520D03*
Y1946890D03*
X193385Y1957520D03*
Y1946890D03*
X203385Y32520D03*
Y21890D03*
X213385Y32520D03*
Y21890D03*
X203385Y196890D03*
X213385D03*
X203385Y207520D03*
X213385D03*
X203385Y371890D03*
X213385D03*
X203385Y382520D03*
X213385D03*
X203386Y557520D03*
Y546890D03*
X213386Y557520D03*
Y546890D03*
X203386Y732520D03*
Y721890D03*
X213386Y732520D03*
Y721890D03*
X203385Y896890D03*
X213385D03*
X203385Y907520D03*
X213385D03*
X203385Y1071890D03*
X213385D03*
X203385Y1082520D03*
X213385D03*
X203385Y1257520D03*
Y1246890D03*
X213385Y1257520D03*
Y1246890D03*
X203385Y1432520D03*
Y1421890D03*
X213385Y1432520D03*
Y1421890D03*
X203385Y1596890D03*
X213385D03*
X203385Y1607520D03*
X213385D03*
X203385Y1771890D03*
X213385D03*
X203385Y1782520D03*
X213385D03*
X203385Y1957520D03*
Y1946890D03*
X213385Y1957520D03*
Y1946890D03*
X223385Y32520D03*
Y21890D03*
X233385Y32520D03*
Y21890D03*
X243385Y32520D03*
Y21890D03*
X223385Y196890D03*
X233385D03*
X243385D03*
X223385Y207520D03*
X233385D03*
X243385D03*
X223385Y371890D03*
X233385D03*
X243385D03*
X223385Y382520D03*
X233385D03*
X243385D03*
X223386Y557520D03*
Y546890D03*
X233386Y557520D03*
Y546890D03*
X243386Y557520D03*
Y546890D03*
X223386Y732520D03*
Y721890D03*
X233386Y732520D03*
Y721890D03*
X243386Y732520D03*
Y721890D03*
X223385Y896890D03*
X233385D03*
X243385D03*
X223385Y907520D03*
X233385D03*
X243385D03*
X223385Y1071890D03*
X233385D03*
X243385D03*
X223385Y1082520D03*
X233385D03*
X243385D03*
X223385Y1257520D03*
Y1246890D03*
X233385Y1257520D03*
Y1246890D03*
X243385Y1257520D03*
Y1246890D03*
X223385Y1432520D03*
Y1421890D03*
X233385Y1432520D03*
Y1421890D03*
X243385Y1432520D03*
Y1421890D03*
X223385Y1596890D03*
X233385D03*
X243385D03*
X223385Y1607520D03*
X233385D03*
X243385D03*
X223385Y1771890D03*
X233385D03*
X243385D03*
X223385Y1782520D03*
X233385D03*
X243385D03*
X223385Y1957520D03*
Y1946890D03*
X233385Y1957520D03*
Y1946890D03*
X243385Y1957520D03*
Y1946890D03*
X337165Y34705D03*
Y199705D03*
Y384705D03*
X337166Y549705D03*
Y734705D03*
X337165Y899705D03*
Y1084705D03*
Y1249705D03*
Y1434705D03*
Y1599705D03*
Y1949705D03*
X342165Y29705D03*
X347165Y24705D03*
X352165Y19705D03*
Y29705D03*
X347165Y34705D03*
X342165Y194705D03*
X357165Y199705D03*
X362165Y194705D03*
X357165Y209705D03*
X362165Y204705D03*
X352165Y369705D03*
X342165Y379705D03*
X347165Y374705D03*
Y384705D03*
X352165Y379705D03*
X342166Y544705D03*
X357166Y549705D03*
Y559705D03*
X362166Y544705D03*
Y554705D03*
X342166Y729705D03*
X347166Y724705D03*
X352166Y719705D03*
Y729705D03*
X347166Y734705D03*
X342165Y894705D03*
X357165Y899705D03*
X362165Y894705D03*
X357165Y909705D03*
X362165Y904705D03*
X352165Y1069705D03*
X342165Y1079705D03*
X347165Y1074705D03*
Y1084705D03*
X352165Y1079705D03*
X342165Y1244705D03*
X357165Y1249705D03*
Y1259705D03*
X362165Y1244705D03*
Y1254705D03*
X342165Y1429705D03*
X347165Y1424705D03*
Y1434705D03*
X352165Y1419705D03*
Y1429705D03*
X342165Y1594705D03*
X357165Y1599705D03*
X362165Y1594705D03*
X357165Y1609705D03*
X362165Y1604705D03*
X352165Y1769705D03*
X347165Y1774705D03*
Y1784705D03*
X352165Y1779705D03*
X342165Y1944705D03*
X357165Y1949705D03*
Y1959705D03*
X362165Y1944705D03*
Y1954705D03*
G54D18*
G01X60815Y1019026D02*
Y1006877D01*
X73556Y994136D01*
X110818D01*
X116118Y988836D01*
X172220D01*
X173342Y989958D01*
X175742D01*
G01X63577Y1019115D02*
Y1008066D01*
X74903Y996740D01*
X111349D01*
X113967Y999358D01*
X173751D01*
X175449Y997660D01*
G01X76446Y1014871D02*
Y1011998D01*
X83040Y1005404D01*
X111094D01*
X115094Y1009404D01*
X159148D01*
X161520Y1007032D01*
X174000D01*
X175698Y1008730D01*
G01X79499Y1014871D02*
Y1013339D01*
X84613Y1008225D01*
X106505D01*
X117473Y1019193D01*
X151873D01*
X156009Y1015057D01*
X171834D01*
X173073Y1016296D01*
X175473D01*
G01X257125Y115559D02*
X253079Y119605D01*
X237800D01*
X199955Y81760D01*
X156054D01*
X154945Y82869D01*
X137458D01*
X127836Y73247D01*
X114348D01*
X113345Y72244D01*
X107263D01*
G01X112836Y769122D02*
X127625D01*
X137564Y779061D01*
X149483D01*
X150933Y777611D01*
X177299D01*
X194109Y794421D01*
X215752D01*
X236367Y815036D01*
X252843D01*
X255687Y812192D01*
G01X105395Y972040D02*
X113199D01*
X115983Y969256D01*
X171901D01*
X175135Y972490D01*
G01X102611Y972220D02*
Y974646D01*
X107191Y979226D01*
X171567D01*
X172622Y980281D01*
X175022D01*
G01X301734Y1513883D02*
X297996Y1517621D01*
X248603D01*
X221966Y1490984D01*
X183263D01*
X166211Y1473932D01*
X152044D01*
X150679Y1475297D01*
X136271D01*
X125946Y1464972D01*
X114038D01*
X108574Y1463389D01*
G01X280240Y1858668D02*
X279040Y1859868D01*
X257788D01*
X233121Y1835201D01*
X189056D01*
X167071Y1813216D01*
X112317D01*
X111219Y1812118D01*
X108819D01*
G01X158901Y85017D02*
X198605D01*
X236450Y122862D01*
X251533D01*
X256947Y128276D01*
G01X255837Y823626D02*
X252883Y820672D01*
X237235D01*
X214707Y798144D01*
X192228D01*
X175066Y780982D01*
X158956D01*
G01X159216Y1477124D02*
X164276D01*
X181803Y1494651D01*
X221119D01*
X247280Y1520812D01*
X298678D01*
X302267Y1524401D01*
G01X279976Y1864565D02*
X278693Y1863282D01*
X256373D01*
X231706Y1838615D01*
X185711D01*
X172183Y1825087D01*
X159075D01*
G54D19*
G01X33263Y790041D02*
X57345Y765959D01*
Y693749D01*
X94725Y656369D01*
Y519167D01*
X74840Y499282D01*
X68708D01*
X42919Y473493D01*
Y455534D01*
X65549Y432904D01*
Y415142D01*
X48559Y398152D01*
Y312675D01*
X76223Y285011D01*
Y223510D01*
X51153Y198440D01*
X26271D01*
X17735Y206976D01*
G01X25389Y786105D02*
X33411D01*
X55945Y763571D01*
Y693169D01*
X93325Y655789D01*
Y520019D01*
X73888Y500582D01*
X68169D01*
X41619Y474032D01*
Y454854D01*
X64149Y432324D01*
Y415722D01*
X47159Y398732D01*
Y312095D01*
X74823Y284431D01*
Y224091D01*
X50572Y199840D01*
X28628D01*
X22735Y205733D01*
Y216976D01*
G01X7673Y805790D02*
X5248Y803365D01*
Y803356D01*
X4923Y803031D01*
Y796775D01*
X10423Y791275D01*
Y788549D01*
X9839Y787965D01*
Y784245D01*
X10423Y783661D01*
Y780675D01*
X9701Y779953D01*
Y776509D01*
X10640Y775570D01*
Y773018D01*
X9783Y772161D01*
Y768553D01*
X10837Y767499D01*
Y765341D01*
X10197Y764701D01*
Y760265D01*
X11910Y758552D01*
Y752678D01*
X14760Y749828D01*
X17936D01*
X24623Y743141D01*
X27320D01*
X31333Y739128D01*
X36594D01*
X38402Y737320D01*
Y673013D01*
X43221Y668193D01*
X75664Y635750D01*
Y526301D01*
X64245Y514882D01*
X62240D01*
X27319Y479961D01*
Y456573D01*
X5501Y434755D01*
Y410441D01*
X15257Y400685D01*
X20519D01*
X30098Y391106D01*
Y251174D01*
X22735Y243811D01*
G01X17735Y233811D02*
X23661Y227885D01*
X41472D01*
X43807Y230220D01*
Y236796D01*
X37944Y242659D01*
Y248504D01*
X34606Y251842D01*
Y392972D01*
X22387Y405191D01*
X16268D01*
X9401Y412058D01*
Y432282D01*
X31219Y454100D01*
Y478344D01*
X63857Y510982D01*
X67706D01*
X80172Y523448D01*
Y637615D01*
X46408Y671380D01*
X42908Y674880D01*
Y749006D01*
X37659Y754255D01*
X31145D01*
X27640Y757760D01*
X23002D01*
X18551Y762211D01*
Y798849D01*
X15547Y801853D01*
G01X7673Y797915D02*
X11497Y794091D01*
Y792300D01*
X11965Y791832D01*
Y788252D01*
X11247Y787534D01*
Y784676D01*
X11855Y784068D01*
Y780268D01*
X11137Y779550D01*
Y776912D01*
X11965Y776084D01*
Y772504D01*
X11083Y771622D01*
Y769092D01*
X12141Y768034D01*
Y764806D01*
X11497Y764162D01*
Y760804D01*
X14796Y757505D01*
X16540D01*
X24449Y749596D01*
X27951D01*
X31701Y745846D01*
X34104D01*
X39802Y740148D01*
Y673593D01*
X44211Y669183D01*
X76966Y636428D01*
Y525762D01*
X64786Y513582D01*
X62779D01*
X28619Y479422D01*
Y455893D01*
X6801Y434075D01*
Y410980D01*
X15696Y402085D01*
X20959D01*
X31400Y391644D01*
Y248221D01*
X28710Y245531D01*
Y242836D01*
X37735Y233811D01*
G01X15547Y809727D02*
X12797Y806977D01*
Y792839D01*
X13318Y792318D01*
Y787766D01*
X12797Y787245D01*
Y784965D01*
X13291Y784471D01*
Y779865D01*
X12797Y779371D01*
Y777091D01*
X13401Y776487D01*
Y772101D01*
X12573Y771273D01*
Y769441D01*
X13441Y768573D01*
Y764267D01*
X12797Y763623D01*
Y761343D01*
X15030Y759110D01*
X16997D01*
X24906Y751201D01*
X28616D01*
X32366Y747451D01*
X37789D01*
X41407Y743833D01*
Y674258D01*
X45346Y670318D01*
X78366Y637298D01*
Y525182D01*
X65466Y512282D01*
X63318D01*
X29919Y478883D01*
Y454923D01*
X8101Y433105D01*
Y411519D01*
X15930Y403690D01*
X21334D01*
X33105Y391919D01*
Y251237D01*
X36443Y247899D01*
Y240787D01*
X41235Y235995D01*
Y232361D01*
X38306Y229432D01*
X32114D01*
X27735Y233811D01*
G01X7673Y821538D02*
X16546D01*
X22596Y815488D01*
Y768928D01*
X24700Y766824D01*
X28747D01*
X32200Y763371D01*
X36937D01*
X47108Y753200D01*
Y676620D01*
X49378Y674350D01*
X84372Y639355D01*
Y521488D01*
X69966Y507082D01*
X65474D01*
X35119Y476727D01*
Y452060D01*
X13601Y430542D01*
Y413798D01*
X18008Y409391D01*
X24127D01*
X38806Y394712D01*
Y257740D01*
X52735Y243811D01*
G01X7673Y813664D02*
X16117D01*
X19867Y809914D01*
Y762875D01*
X23582Y759160D01*
X28220D01*
X31725Y755655D01*
X38239D01*
X44308Y749586D01*
Y675460D01*
X47398Y672370D01*
X81572Y638195D01*
Y522868D01*
X68386Y509682D01*
X64396D01*
X32519Y477805D01*
Y453420D01*
X10801Y431702D01*
Y412638D01*
X16848Y406591D01*
X22967D01*
X36006Y393552D01*
Y252678D01*
X39344Y249340D01*
Y247202D01*
X42735Y243811D01*
G01X15547Y817601D02*
X21196Y811952D01*
Y768348D01*
X24120Y765424D01*
X28167D01*
X31620Y761971D01*
X36357D01*
X45708Y752620D01*
Y676040D01*
X48388Y673360D01*
X82972Y638775D01*
Y521927D01*
X69427Y508382D01*
X64935D01*
X33819Y477266D01*
Y452740D01*
X12201Y431122D01*
Y413218D01*
X17428Y407991D01*
X23547D01*
X37406Y394132D01*
Y255058D01*
X47735Y244729D01*
Y233811D01*
G01X318088Y231820D02*
X306246Y243662D01*
X302814D01*
X202108Y344368D01*
X98124D01*
X76284Y366208D01*
Y435414D01*
X98773Y457903D01*
Y658745D01*
X60595Y696923D01*
Y777713D01*
X38579Y799729D01*
Y862210D01*
X35515Y865274D01*
X31467D01*
X27173Y869568D01*
X18698D01*
X15547Y872719D01*
G01X7673Y868782D02*
X16076D01*
X16590Y868268D01*
X26164D01*
X30458Y863974D01*
X34118D01*
X37231Y860861D01*
Y798332D01*
X59185Y776378D01*
Y695098D01*
X97381Y656902D01*
Y458801D01*
X74307Y435727D01*
Y366190D01*
X97539Y342958D01*
X200909D01*
X317888Y225979D01*
X320372D01*
G01X15547Y880593D02*
X18992Y877148D01*
X28437D01*
X32465Y873120D01*
X38966D01*
X41273Y870813D01*
Y802155D01*
X63858Y779570D01*
Y699678D01*
X101511Y662025D01*
Y455252D01*
X79608Y433349D01*
Y368135D01*
X100650Y347093D01*
X209196D01*
X303741Y252548D01*
Y250357D01*
X307277Y246821D01*
X309468D01*
X324709Y231580D01*
G01X7673Y876656D02*
X7684Y876645D01*
X17382D01*
X18270Y875757D01*
X27860D01*
X31888Y871729D01*
X38389D01*
X39881Y870237D01*
Y800987D01*
X62151Y778717D01*
Y698420D01*
X100166Y660405D01*
Y456602D01*
X78081Y434517D01*
Y367247D01*
X99583Y345745D01*
X204142D01*
X304751Y245136D01*
X307940D01*
X314914Y238162D01*
G01X33263Y908152D02*
X24708D01*
X22356Y905800D01*
Y901711D01*
X24916Y899151D01*
X27095D01*
X30954Y895292D01*
X36839D01*
X59503Y872628D01*
Y868895D01*
X90851Y837547D01*
Y797323D01*
X73436Y779908D01*
Y705551D01*
X109663Y669324D01*
Y448523D01*
X88710Y427570D01*
Y372453D01*
X105448Y355715D01*
X218234D01*
X303171Y270778D01*
X311066D01*
X350489Y231355D01*
X369907D01*
X396449Y204813D01*
Y80371D01*
X372204Y56126D01*
G01X7673Y892404D02*
X16323Y883754D01*
X27015D01*
X30645Y880124D01*
X37943D01*
X42620Y875447D01*
Y803099D01*
X65293Y780426D01*
Y700665D01*
X102859Y663099D01*
Y454085D01*
X81224Y432450D01*
Y368613D01*
X101444Y348393D01*
X211643D01*
X321899Y238137D01*
G01X331046Y232021D02*
X310814Y252253D01*
Y257136D01*
X306350Y261600D01*
X301467D01*
X213327Y349740D01*
X102637D01*
X82751Y369626D01*
Y430924D01*
X104297Y452470D01*
Y664267D01*
X66774Y701790D01*
Y781369D01*
X43967Y804176D01*
Y876005D01*
X38501Y881471D01*
X31203D01*
X27573Y885101D01*
X18913D01*
X15547Y888467D01*
G01Y927837D02*
X18650D01*
X23083Y923404D01*
X27591D01*
X31958Y919037D01*
X75533D01*
X79700Y914870D01*
Y867981D01*
X95395Y852286D01*
Y794888D01*
X81009Y780502D01*
Y709426D01*
X101168Y689267D01*
X239372D01*
X329636Y599003D01*
Y584715D01*
G01X7673Y931774D02*
X16618D01*
X23641Y924751D01*
X28422D01*
X32789Y920384D01*
X76091D01*
X82947Y913528D01*
Y866639D01*
X96742Y852844D01*
Y793820D01*
X83614Y780692D01*
Y709336D01*
X102336Y690614D01*
X239930D01*
X331867Y598677D01*
Y589810D01*
G01X7673Y939648D02*
X7684Y939637D01*
X13905D01*
X14672Y938870D01*
X18093D01*
X24245Y932718D01*
X27652D01*
X31640Y928730D01*
X72357D01*
X85764Y915323D01*
Y868142D01*
X99807Y854099D01*
Y793013D01*
X88152Y781358D01*
Y711010D01*
X105685Y693477D01*
X241268D01*
X241675Y693070D01*
X241676D01*
X335551Y599195D01*
Y579043D01*
X336616Y577978D01*
G01X7673Y947522D02*
X7684Y947511D01*
X16781D01*
X18459Y945833D01*
Y944113D01*
X23463Y939109D01*
X27056D01*
X30874Y935291D01*
X72981D01*
X78974Y929298D01*
Y923975D01*
X87068Y915881D01*
Y869710D01*
X101319Y855459D01*
Y792265D01*
X89564Y780510D01*
Y713086D01*
X107459Y695191D01*
X241541D01*
X337387Y599345D01*
Y586230D01*
G01X15547Y935711D02*
X15558Y935700D01*
X19384D01*
X23694Y931390D01*
X27017D01*
X31005Y927402D01*
X71437D01*
X84384Y914455D01*
Y867306D01*
X98471Y853219D01*
Y793640D01*
X86523Y781692D01*
Y709412D01*
X103892Y692043D01*
X240649D01*
X333750Y598942D01*
Y595326D01*
G01X15547Y951459D02*
X20200Y946806D01*
Y944405D01*
X24059Y940546D01*
X27605D01*
X31423Y936728D01*
X73577D01*
X80411Y929894D01*
Y924571D01*
X88427Y916555D01*
Y870384D01*
X102756Y856055D01*
Y791825D01*
X90899Y779968D01*
Y715164D01*
X109435Y696628D01*
X242137D01*
X339151Y599614D01*
Y583875D01*
X342900Y580126D01*
G01X7673Y1002640D02*
X16122D01*
X19301Y999461D01*
Y996921D01*
X22090Y994132D01*
X26828D01*
X31069Y989891D01*
X35617D01*
X43347Y997621D01*
Y1004516D01*
X67181Y1028350D01*
X187632D01*
X190374Y1025608D01*
X251932D01*
X318557Y958983D01*
Y941178D01*
G01X323868Y929978D02*
Y942694D01*
X326014Y944840D01*
Y953669D01*
X252603Y1027080D01*
X191016D01*
X188369Y1029727D01*
X66388D01*
X41894Y1005233D01*
Y998232D01*
X35012Y991350D01*
X31674D01*
X27433Y995591D01*
X22695D01*
X20760Y997526D01*
Y1001364D01*
X15547Y1006577D01*
G01X7673Y1010514D02*
X15912D01*
X20485Y1005941D01*
Y1004027D01*
X22186Y1002326D01*
X26559D01*
X30934Y997951D01*
X35672D01*
X39799Y1002078D01*
Y1005095D01*
X71540Y1036836D01*
X244939D01*
X329938Y951837D01*
Y948756D01*
G01X15547Y1014451D02*
X21916Y1008082D01*
Y1004620D01*
X22873Y1003663D01*
X27246D01*
X31527Y999382D01*
X35079D01*
X37965Y1002268D01*
Y1005103D01*
X71000Y1038138D01*
X245567D01*
X332527Y951178D01*
Y943746D01*
G01X15547Y1022325D02*
X19028Y1018844D01*
Y1014045D01*
X23007Y1010066D01*
X26714D01*
X30535Y1006245D01*
X36521D01*
X69852Y1039576D01*
X246647D01*
X334550Y951673D01*
Y938872D01*
X336160Y937262D01*
G01X343656Y933725D02*
X335921Y941460D01*
Y952241D01*
X247150Y1041013D01*
X69256D01*
X35921Y1007678D01*
X31109D01*
X27302Y1011485D01*
X23595D01*
X20447Y1014633D01*
Y1021916D01*
X16101Y1026262D01*
X7673D01*
G01X7677Y1101062D02*
X16284D01*
X19799Y1097547D01*
Y1096209D01*
X23834Y1092174D01*
X27340D01*
X31022Y1088492D01*
X37478D01*
X72592Y1053378D01*
X287858D01*
X291446Y1056966D01*
X371999D01*
X393398Y1078365D01*
Y1137839D01*
X379335Y1151902D01*
Y1189778D01*
G01X15551Y1104999D02*
X21135Y1099415D01*
Y1096763D01*
X24388Y1093510D01*
X27894D01*
X31576Y1089828D01*
X38448D01*
X73268Y1055008D01*
X282604D01*
X286089Y1058493D01*
X371687D01*
X392098Y1078904D01*
Y1137300D01*
X376472Y1152926D01*
Y1194999D01*
G01X383276Y1184136D02*
Y1150289D01*
X395044Y1138521D01*
Y1077683D01*
X372559Y1055198D01*
X302814D01*
X299626Y1052010D01*
X72020D01*
X45984Y1078046D01*
X42143Y1081876D01*
X31721D01*
X27683Y1085914D01*
X24178D01*
X20565Y1089527D01*
Y1092111D01*
X15551Y1097125D01*
G01X7677Y1093188D02*
X16096D01*
X19265Y1090019D01*
Y1088988D01*
X23639Y1084614D01*
X27144D01*
X31520Y1080238D01*
X41579D01*
X71111Y1050706D01*
X318213D01*
X319279Y1049640D01*
X327139D01*
X328205Y1050706D01*
X370227D01*
X396571Y1077050D01*
Y1139154D01*
X386816Y1148909D01*
Y1179841D01*
G01X25393Y1128622D02*
X21175Y1124404D01*
Y1119594D01*
X23391Y1117378D01*
X28550D01*
X31182Y1120010D01*
X87757D01*
X111407Y1143660D01*
Y1375810D01*
X118544Y1382947D01*
X173349D01*
X181402Y1374894D01*
X240591D01*
X317281Y1298204D01*
Y1273664D01*
X328731Y1262214D01*
Y1242280D01*
X361069Y1209942D01*
Y1173889D01*
X334080Y1146900D01*
Y1113027D01*
X337509Y1109598D01*
G01X7677Y1116810D02*
X15592Y1108895D01*
X16743D01*
X18692Y1106946D01*
Y1104960D01*
X23045Y1100607D01*
X27026D01*
X27380Y1100253D01*
Y1100249D01*
X31154Y1096475D01*
X36725D01*
X40718Y1092482D01*
Y1089493D01*
X73835Y1056376D01*
X281172D01*
X285383Y1060587D01*
X371919D01*
X390499Y1079167D01*
Y1136637D01*
X373674Y1153462D01*
Y1199967D01*
G01X15551Y1112873D02*
X20292Y1108132D01*
Y1105623D01*
X23708Y1102207D01*
X27267D01*
X31695Y1097779D01*
X37589D01*
X42514Y1092854D01*
Y1089865D01*
X74470Y1057909D01*
X279319D01*
X283909Y1062499D01*
X371992D01*
X388976Y1079483D01*
Y1135740D01*
X371523Y1153193D01*
Y1204725D01*
G01X7677Y1171929D02*
X10620Y1168986D01*
Y1168957D01*
X11811Y1167766D01*
Y1166860D01*
X15485Y1163186D01*
X26220D01*
X30036Y1159370D01*
X35530D01*
X53251Y1141649D01*
X84606D01*
X98333Y1155376D01*
Y1377485D01*
X113726Y1392878D01*
X373261D01*
X391536Y1411153D01*
Y1527361D01*
X348710Y1570187D01*
G01X15551Y1152244D02*
X18960Y1148835D01*
X27946D01*
X32010Y1144771D01*
X36898D01*
X48986Y1132683D01*
X91529D01*
X105905Y1147059D01*
Y1378310D01*
X115961Y1388366D01*
X258156D01*
X262374Y1384148D01*
X294798D01*
X299016Y1388366D01*
X375266D01*
X396143Y1409243D01*
Y1533758D01*
X361011Y1568890D01*
G01X15551Y1175866D02*
Y1173703D01*
X24726Y1164528D01*
X27706D01*
X31183Y1161051D01*
X37986D01*
X55258Y1143779D01*
X84545D01*
X94403Y1153637D01*
Y1375501D01*
X113334Y1394432D01*
X372751D01*
X390077Y1411758D01*
Y1525405D01*
X343402Y1572080D01*
G01X15551Y1160118D02*
X19127Y1156542D01*
X28686D01*
X31960Y1153268D01*
X38383D01*
X53264Y1138387D01*
X87786D01*
X102888Y1153489D01*
Y1379112D01*
X115159Y1391383D01*
X260797D01*
X265068Y1387112D01*
X293580D01*
X297851Y1391383D01*
X374015D01*
X393126Y1410494D01*
Y1530360D01*
X348245Y1575241D01*
G01X7677Y1164055D02*
X16735Y1154997D01*
X28356D01*
X31391Y1151962D01*
X34729D01*
X49664Y1137027D01*
X88350D01*
X104248Y1152925D01*
Y1378631D01*
X115640Y1390023D01*
X259553D01*
X263901Y1385675D01*
X294169D01*
X298517Y1390023D01*
X374579D01*
X394486Y1409930D01*
Y1531868D01*
X355364Y1570990D01*
G01X7677Y1156180D02*
X16391Y1147466D01*
X27347D01*
X31433Y1143380D01*
X36070D01*
X48303Y1131147D01*
X91961D01*
X107296Y1146482D01*
Y1377681D01*
X116590Y1386975D01*
X256224D01*
X260578Y1382621D01*
X295875D01*
X300229Y1386975D01*
X375843D01*
X397534Y1408666D01*
Y1536403D01*
X367829Y1566108D01*
G01X374775Y1919243D02*
X387453Y1906565D01*
Y1775868D01*
X349645Y1738060D01*
X299109D01*
X294796Y1742373D01*
X133837D01*
X113908Y1722444D01*
Y1492658D01*
X85133Y1463883D01*
Y1381292D01*
X83574Y1379733D01*
Y1246647D01*
X52999Y1216072D01*
X28502D01*
X26388Y1218186D01*
X14564D01*
X7677Y1211299D01*
G01X379403Y1917261D02*
X388908Y1907756D01*
Y1774962D01*
X350322Y1736376D01*
X298015D01*
X293410Y1740981D01*
X134478D01*
X115269Y1721772D01*
Y1487378D01*
X86433Y1458542D01*
Y1380753D01*
X84874Y1379194D01*
Y1245913D01*
X53199Y1214238D01*
X31720D01*
X28638Y1211156D01*
X19631D01*
X15551Y1215236D01*
G01Y1230984D02*
X18712Y1234145D01*
X27408D01*
X31140Y1230413D01*
X55651D01*
X79674Y1254436D01*
Y1381350D01*
X81233Y1382909D01*
Y1467262D01*
X109699Y1495728D01*
Y1725606D01*
X130780Y1746687D01*
X300335D01*
X303657Y1743365D01*
X348100D01*
X383295Y1778560D01*
Y1898379D01*
X363361Y1918313D01*
G01X358318Y1920680D02*
X381950Y1897048D01*
Y1779054D01*
X348198Y1745302D01*
X303824D01*
X300955Y1748171D01*
X129596D01*
X108083Y1726658D01*
Y1496780D01*
X79639Y1468336D01*
Y1383154D01*
X78374Y1381889D01*
Y1261569D01*
X48581Y1231776D01*
X32101D01*
X28039Y1235838D01*
X8594D01*
X7677Y1234921D01*
G01X15551Y1223110D02*
X20157Y1227716D01*
X28022D01*
X31947Y1223791D01*
X51832D01*
X80974Y1252933D01*
Y1380811D01*
X82533Y1382370D01*
Y1466022D01*
X111079Y1494568D01*
Y1724446D01*
X131983Y1745350D01*
X297292D01*
X301045Y1741597D01*
X348583D01*
X384687Y1777701D01*
Y1902183D01*
X363411Y1923459D01*
G01X7677Y1219173D02*
X8371Y1219867D01*
X17045D01*
X23327Y1226149D01*
X26914D01*
X31030Y1222033D01*
X52154D01*
X82274Y1252153D01*
Y1380272D01*
X83833Y1381831D01*
Y1465033D01*
X112471Y1493671D01*
Y1723549D01*
X132868Y1743946D01*
X295497D01*
X299699Y1739744D01*
X349133D01*
X386126Y1776737D01*
Y1905417D01*
X369748Y1921795D01*
G01X32735Y1957291D02*
X37005Y1961561D01*
X54022D01*
X56702Y1958881D01*
Y1950576D01*
X34643Y1928517D01*
Y1854610D01*
X66437Y1822816D01*
Y1613933D01*
X44161Y1591657D01*
Y1549204D01*
X34443Y1539486D01*
Y1500472D01*
X43908Y1491007D01*
Y1325400D01*
X35251Y1316743D01*
X31559D01*
X27581Y1312765D01*
X24464D01*
X22591Y1310892D01*
Y1297127D01*
X21160Y1295696D01*
Y1291711D01*
X15551Y1286102D01*
G01X32735Y2061661D02*
Y2055452D01*
X33670Y2054517D01*
Y2019870D01*
X94658Y1958882D01*
Y1853646D01*
X74509Y1833497D01*
Y1619865D01*
X79488Y1614886D01*
Y1572718D01*
X41397Y1534627D01*
Y1503995D01*
X54113Y1491279D01*
Y1311040D01*
X44551Y1301478D01*
X31901D01*
X27991Y1297568D01*
X24996D01*
X22460Y1295032D01*
Y1292553D01*
X24974Y1290039D01*
X33267D01*
G01X7677Y1297913D02*
X13074D01*
X13381Y1298220D01*
X16192D01*
X18433Y1300461D01*
Y1313928D01*
X20374Y1315869D01*
Y1318697D01*
X24087Y1322410D01*
X27390D01*
X31213Y1326233D01*
X34288D01*
X40008Y1331953D01*
Y1489390D01*
X30543Y1498855D01*
Y1543594D01*
X38238Y1551289D01*
Y1591251D01*
X62537Y1615550D01*
Y1821199D01*
X30743Y1852993D01*
Y1940128D01*
X33546Y1942931D01*
Y1948102D01*
X42735Y1957291D01*
G01X47735Y1947291D02*
X33343Y1932899D01*
Y1854071D01*
X65137Y1822277D01*
Y1614472D01*
X42543Y1591878D01*
Y1550201D01*
X33143Y1540801D01*
Y1499933D01*
X42608Y1490468D01*
Y1326349D01*
X34539Y1318280D01*
X30760D01*
X26630Y1314150D01*
X23446D01*
X21194Y1311898D01*
Y1297795D01*
X17375Y1293976D01*
X15551D01*
G01X27735Y1947291D02*
Y1852323D01*
X59937Y1820121D01*
Y1616628D01*
X33936Y1590627D01*
Y1551559D01*
X27943Y1545566D01*
Y1497777D01*
X37408Y1488312D01*
Y1335769D01*
X35430Y1333791D01*
X31300D01*
X27696Y1330187D01*
X23677D01*
X20711Y1327221D01*
Y1323597D01*
X17873Y1320759D01*
X14681D01*
X12257Y1318335D01*
Y1305144D01*
X15551Y1301850D01*
G01X17735Y1947291D02*
Y1959548D01*
X21417Y1963230D01*
X24757D01*
X27788Y1960199D01*
Y1955481D01*
X31546Y1951723D01*
Y1943957D01*
X29327Y1941738D01*
Y1852570D01*
X61237Y1820660D01*
Y1616089D01*
X35922Y1590774D01*
Y1551095D01*
X29243Y1544416D01*
Y1498316D01*
X38708Y1488851D01*
Y1335104D01*
X35770Y1332166D01*
X31872D01*
X28397Y1328691D01*
X24115D01*
X22512Y1327088D01*
Y1323158D01*
X18733Y1319379D01*
Y1316435D01*
X15551Y1313253D01*
Y1309724D01*
G01X52735Y1957291D02*
X41982Y1946538D01*
Y1943722D01*
X32043Y1933783D01*
Y1853532D01*
X63837Y1821738D01*
Y1615011D01*
X40391Y1591565D01*
Y1550827D01*
X31843Y1542279D01*
Y1499394D01*
X41308Y1489929D01*
Y1331413D01*
X34503Y1324608D01*
X32399D01*
X28620Y1320829D01*
X24709D01*
X21798Y1317918D01*
Y1314666D01*
X19876Y1312744D01*
Y1299751D01*
X16851Y1296726D01*
X14364D01*
X7677Y1290039D01*
G01X22735Y1957291D02*
Y1941745D01*
X26404Y1938076D01*
Y1851815D01*
X58637Y1819582D01*
Y1617167D01*
X32029Y1590559D01*
Y1552987D01*
X26643Y1547601D01*
Y1497238D01*
X36108Y1487773D01*
Y1349673D01*
X31989Y1345554D01*
Y1340804D01*
X27903Y1336718D01*
X24178D01*
X19202Y1331742D01*
Y1324458D01*
X17111Y1322367D01*
X14390D01*
X10509Y1318486D01*
Y1312076D01*
X7677Y1309244D01*
Y1305787D01*
G01X33267Y1313661D02*
X47973D01*
X48719Y1314407D01*
Y1315107D01*
X48730Y1315118D01*
Y1316568D01*
X48719Y1316579D01*
Y1320107D01*
X48730Y1320118D01*
Y1321568D01*
X48719Y1321579D01*
Y1325107D01*
X48730Y1325118D01*
Y1326568D01*
X48719Y1326579D01*
Y1330107D01*
X48730Y1330118D01*
Y1331568D01*
X48719Y1331579D01*
Y1335107D01*
X48730Y1335118D01*
Y1336568D01*
X48719Y1336579D01*
Y1340107D01*
X48730Y1340118D01*
Y1341568D01*
X48719Y1341579D01*
Y1345107D01*
X48730Y1345118D01*
Y1346568D01*
X48719Y1346579D01*
Y1489043D01*
X36003Y1501759D01*
Y1536863D01*
X74094Y1574954D01*
Y1611621D01*
X69115Y1616600D01*
Y1835733D01*
X89264Y1855882D01*
Y1956646D01*
X28276Y2017634D01*
Y2041120D01*
X17735Y2051661D01*
G01X25393Y1309724D02*
X46145D01*
X50213Y1313792D01*
Y1489661D01*
X37496Y1502378D01*
Y1505612D01*
X37497Y1505613D01*
Y1536244D01*
X75588Y1574335D01*
Y1612524D01*
X70609Y1617503D01*
Y1835114D01*
X90758Y1855263D01*
Y1957265D01*
X29770Y2018253D01*
Y2041720D01*
X22735Y2048755D01*
Y2061661D01*
G01X33263Y782167D02*
X54545Y760885D01*
Y692589D01*
X91925Y655209D01*
Y520458D01*
X73349Y501882D01*
X67630D01*
X40319Y474571D01*
Y454174D01*
X62749Y431744D01*
Y416302D01*
X45759Y399312D01*
Y311515D01*
X73423Y283851D01*
Y224671D01*
X49992Y201240D01*
X33471D01*
X27735Y206976D01*
G01X25389Y778231D02*
X35101D01*
X53145Y760187D01*
Y692009D01*
X90525Y654629D01*
Y521298D01*
X72409Y503182D01*
X67091D01*
X39019Y475110D01*
Y453494D01*
X61349Y431164D01*
Y416882D01*
X44359Y399892D01*
Y310935D01*
X72023Y283271D01*
Y225251D01*
X49412Y202640D01*
X45423D01*
X42735Y205328D01*
Y216976D01*
G01X33263Y774293D02*
X51745Y755811D01*
Y691429D01*
X89125Y654049D01*
Y522290D01*
X71317Y504482D01*
X66552D01*
X37719Y475649D01*
Y452814D01*
X59949Y430584D01*
Y417462D01*
X42959Y400472D01*
Y310355D01*
X70623Y282691D01*
Y228630D01*
X54344Y212351D01*
X53110D01*
X47735Y206976D01*
G01X25389Y770357D02*
X34884D01*
X50345Y754896D01*
Y690849D01*
X87725Y653469D01*
Y522870D01*
X70637Y505782D01*
X66013D01*
X36419Y476188D01*
Y452134D01*
X58549Y430004D01*
Y418042D01*
X41559Y401052D01*
Y309775D01*
X69223Y282111D01*
Y233464D01*
X52735Y216976D01*
G01X48433Y866179D02*
X51423D01*
X86577Y831025D01*
Y800968D01*
X68667Y783058D01*
Y702013D01*
X105610Y665070D01*
Y450964D01*
X84114Y429468D01*
Y370986D01*
X104054Y351046D01*
X215504D01*
X302216Y264334D01*
X310732D01*
X325762Y249304D01*
Y245923D01*
X345414Y226271D01*
X368053D01*
X392235Y202089D01*
Y84493D01*
X359931Y52189D01*
G01X48467Y869278D02*
X50475D01*
X88070Y831683D01*
Y799996D01*
X70199Y782125D01*
Y703023D01*
X107011Y666211D01*
Y449792D01*
X85450Y428231D01*
Y371865D01*
X104836Y352479D01*
X216352D01*
X303170Y265661D01*
X312473D01*
X349972Y228162D01*
X368508D01*
X393668Y203002D01*
Y82991D01*
X387524Y76847D01*
G01X25389Y904215D02*
X32863Y896741D01*
X40387D01*
X61608Y875520D01*
Y873034D01*
X92468Y842174D01*
Y796027D01*
X75541Y779100D01*
Y706423D01*
X111140Y670824D01*
Y448156D01*
X90106Y427122D01*
Y372896D01*
X105182Y357820D01*
X219106D01*
X304564Y272362D01*
X311756D01*
X350658Y233460D01*
X370779D01*
X397938Y206301D01*
Y76807D01*
X379572Y58441D01*
G01X25389Y896341D02*
X32264Y889466D01*
X40144D01*
X57720Y871890D01*
Y864743D01*
X89549Y832914D01*
Y799165D01*
X71653Y781269D01*
Y704812D01*
X108329Y668136D01*
Y449050D01*
X87003Y427724D01*
Y372185D01*
X105256Y353932D01*
X217495D01*
X304342Y267085D01*
X312907D01*
X350420Y229572D01*
X369168D01*
X395037Y203703D01*
Y81653D01*
X365720Y52336D01*
G01X33263Y900278D02*
X39171D01*
X62633Y876816D01*
X63249D01*
X93815Y846250D01*
Y795166D01*
X77182Y778533D01*
Y707103D01*
X112467Y671818D01*
Y447632D01*
X91473Y426638D01*
Y373489D01*
X105501Y359461D01*
X219786D01*
X302574Y276673D01*
X309887D01*
X351459Y235101D01*
X371459D01*
X399579Y206981D01*
Y72470D01*
X379257Y52148D01*
G01X33263Y947522D02*
X33274Y947511D01*
X70881D01*
X85109Y933283D01*
Y926031D01*
X103945Y907195D01*
Y862731D01*
X106852Y859824D01*
Y789352D01*
X99061Y781561D01*
Y755221D01*
X103236Y751046D01*
Y715285D01*
X117094Y701427D01*
X242982D01*
X309793Y634616D01*
X360324D01*
X394138Y600802D01*
Y426553D01*
X374442Y406857D01*
G01X25389Y943585D02*
X25400Y943574D01*
X29349D01*
X30479Y942444D01*
X71515D01*
X81975Y931984D01*
Y925362D01*
X94625Y912712D01*
Y866541D01*
X104113Y857053D01*
Y791048D01*
X92499Y779434D01*
Y716348D01*
X110554Y698293D01*
X242327D01*
X309138Y631482D01*
X359025D01*
X391004Y599503D01*
Y428947D01*
X363825Y401768D01*
G01X25389Y959333D02*
X29234Y955488D01*
Y946712D01*
X31620Y944326D01*
X72175D01*
X83772Y932729D01*
Y925477D01*
X96059Y913190D01*
Y867649D01*
X105505Y858203D01*
Y789967D01*
X97354Y781816D01*
Y755088D01*
X101852Y750590D01*
Y714510D01*
X116272Y700090D01*
X242428D01*
X309239Y633279D01*
X359770D01*
X392801Y600248D01*
Y428202D01*
X368907Y404308D01*
G01X33263Y955396D02*
X33274Y955385D01*
X65255D01*
X86698Y933942D01*
Y926690D01*
X105248Y908140D01*
Y863676D01*
X108153Y860771D01*
Y788605D01*
X102994Y783446D01*
Y753558D01*
X104536Y752016D01*
Y716233D01*
X117753Y703016D01*
X243641D01*
X310452Y636205D01*
X360983D01*
X395727Y601461D01*
Y425220D01*
X380619Y410112D01*
G01X33263Y963270D02*
X33274Y963259D01*
X61722D01*
X89711Y935270D01*
Y927739D01*
X107993Y909457D01*
Y864916D01*
X110821Y862088D01*
Y716151D01*
X121139Y705833D01*
X244809D01*
X311620Y639022D01*
X362151D01*
X398544Y602629D01*
Y421665D01*
X380878Y403999D01*
G01X25389Y967207D02*
X32776Y959820D01*
X62731D01*
X88245Y934306D01*
Y927184D01*
X106645Y908784D01*
Y864190D01*
X109518Y861317D01*
Y787579D01*
X104776Y782837D01*
Y759622D01*
X109342Y755056D01*
Y715556D01*
X120531Y704367D01*
X244201D01*
X311012Y637556D01*
X361543D01*
X397078Y602021D01*
Y423818D01*
X374542Y401282D01*
G01X33263Y1010514D02*
X65186Y1042437D01*
X249598D01*
X315782Y976253D01*
X367121D01*
X391691Y951683D01*
Y781897D01*
X362577Y752783D01*
G01X382892Y767710D02*
X394415Y779233D01*
Y953528D01*
X368528Y979415D01*
X317117D01*
X251375Y1045157D01*
X47996D01*
X29579Y1026740D01*
Y1018641D01*
X25389Y1014451D01*
G01X33263Y1026262D02*
X50774Y1043773D01*
X250543D01*
X316336Y977980D01*
X367707D01*
X393027Y952660D01*
Y780575D01*
X386790Y774338D01*
G01X380186Y761742D02*
X396230Y777786D01*
Y954280D01*
X369476Y981034D01*
X317375D01*
X251785Y1046624D01*
X46498D01*
X25389Y1025515D01*
Y1022325D01*
G01X391278Y765979D02*
X399722Y774423D01*
Y955728D01*
X370130Y985320D01*
X317582D01*
X253541Y1049361D01*
X41661D01*
X33267Y1057755D01*
Y1061692D01*
G01X376654Y754748D02*
X398022Y776116D01*
Y955023D01*
X369353Y983692D01*
X317054D01*
X252721Y1048025D01*
X39060D01*
X25393Y1061692D01*
Y1065629D01*
G01X328989Y1121090D02*
Y1147201D01*
X357257Y1175469D01*
Y1208362D01*
X320155Y1245464D01*
Y1266792D01*
X314455Y1272492D01*
Y1297032D01*
X239688Y1371799D01*
X179033D01*
X170711Y1380121D01*
X119806D01*
X114233Y1374548D01*
Y1142230D01*
X88836Y1116834D01*
X41165D01*
X33267Y1108936D01*
G01Y1116810D02*
X34839Y1118382D01*
X88162D01*
X112844Y1143064D01*
Y1375214D01*
X119140Y1381510D01*
X172285D01*
X180613Y1373182D01*
X240270D01*
X315844Y1297608D01*
Y1273068D01*
X327294Y1261618D01*
Y1241684D01*
X359632Y1209346D01*
Y1174485D01*
X331920Y1146773D01*
Y1116088D01*
G01X326558Y1126368D02*
Y1146998D01*
X355682Y1176122D01*
Y1207709D01*
X318580Y1244811D01*
Y1266139D01*
X312880Y1271839D01*
Y1296379D01*
X238853Y1370406D01*
X178154D01*
X170014Y1378546D01*
X120144D01*
X115808Y1374210D01*
Y1141735D01*
X89399Y1115326D01*
X43730D01*
X33403Y1104999D01*
X25393D01*
G01X344099Y1106798D02*
X335380Y1115517D01*
Y1146295D01*
X362416Y1173331D01*
Y1210500D01*
X330078Y1242838D01*
Y1262772D01*
X318628Y1274222D01*
Y1298762D01*
X240851Y1376539D01*
X182114D01*
X174359Y1384294D01*
X117986D01*
X110060Y1376368D01*
Y1144777D01*
X86659Y1121376D01*
X29550D01*
X28922Y1120748D01*
X25393D01*
G01X33267Y1124684D02*
X87889D01*
X92917Y1129712D01*
X108705Y1145499D01*
Y1376930D01*
X117424Y1385649D01*
X233658D01*
X319983Y1299324D01*
Y1274784D01*
X331433Y1263334D01*
Y1243400D01*
X363771Y1211062D01*
Y1172769D01*
X337039Y1146037D01*
Y1117118D01*
X349855Y1104302D01*
G01X33267Y1164055D02*
X41642Y1172430D01*
Y1176080D01*
X52887Y1187325D01*
Y1193647D01*
X92811Y1233571D01*
Y1375855D01*
X115843Y1398887D01*
X154924D01*
X158563Y1402526D01*
X164370D01*
X170224Y1396672D01*
X344155D01*
X350690Y1403207D01*
G01X33267Y1179803D02*
X45250Y1191786D01*
Y1195729D01*
X50606Y1201085D01*
X50607D01*
X88774Y1239252D01*
Y1377577D01*
X90383Y1379186D01*
Y1382625D01*
X111181Y1403423D01*
X152471D01*
X157763Y1408715D01*
X192428D01*
X197720Y1403423D01*
X314183D01*
G01X25393Y1183740D02*
X33656D01*
X41553Y1191637D01*
Y1194457D01*
X87474Y1240378D01*
Y1378116D01*
X89035Y1379677D01*
Y1385044D01*
X101626Y1397635D01*
G01X25393Y1175866D02*
X34076D01*
X48913Y1190703D01*
Y1195793D01*
X90074Y1236954D01*
Y1377038D01*
X91955Y1378919D01*
Y1380844D01*
X112962Y1401851D01*
X153088D01*
X158015Y1406778D01*
X177594D01*
X183026Y1401346D01*
X319404D01*
G01X325636Y1399114D02*
X176594D01*
X170951Y1404757D01*
X158226D01*
X153793Y1400324D01*
X115199D01*
X91374Y1376499D01*
Y1234503D01*
X51212Y1194341D01*
Y1189133D01*
X38978Y1176899D01*
Y1172745D01*
X34225Y1167992D01*
X25393D01*
G01X33267Y1187677D02*
X39284Y1193694D01*
Y1194212D01*
X86174Y1241102D01*
Y1378655D01*
X87733Y1380214D01*
Y1386605D01*
X96510Y1395382D01*
G01X25393Y1238858D02*
X34866D01*
X43374Y1247366D01*
Y1248394D01*
X64940Y1269960D01*
Y1457852D01*
X105103Y1498015D01*
Y1727893D01*
X128275Y1751065D01*
X304294D01*
X307278Y1748081D01*
X325887D01*
X329887Y1752081D01*
G01X33267Y1234921D02*
X46446Y1248100D01*
Y1248789D01*
X77074Y1279417D01*
Y1311229D01*
X73725Y1314578D01*
Y1316028D01*
X77074Y1319377D01*
Y1382428D01*
X78339Y1383693D01*
Y1469005D01*
X106691Y1497357D01*
Y1727235D01*
X128954Y1749498D01*
X302324D01*
X305214Y1746608D01*
X329068D01*
X335730Y1753270D01*
G01X25393Y1246732D02*
X35943D01*
X56293Y1267082D01*
Y1302917D01*
X58893Y1305517D01*
Y1310798D01*
X58013Y1311678D01*
Y1455222D01*
X102065Y1499274D01*
Y1729152D01*
X127058Y1754145D01*
X310893D01*
X311539Y1753499D01*
G01X33267Y1242795D02*
X35496Y1245024D01*
X36458D01*
X60502Y1269068D01*
Y1298644D01*
X63640Y1301782D01*
Y1458707D01*
X103547Y1498614D01*
Y1728538D01*
X127441Y1752432D01*
X306800D01*
X308372Y1750860D01*
X318677D01*
X321283Y1753466D01*
G01X33267Y1305787D02*
X45002D01*
X51513Y1312298D01*
Y1490200D01*
X38796Y1502917D01*
Y1505073D01*
X38797Y1505074D01*
Y1535705D01*
X76888Y1573796D01*
Y1613808D01*
X71909Y1618787D01*
Y1834575D01*
X92058Y1854724D01*
Y1957804D01*
X31070Y2018792D01*
Y2043349D01*
X27735Y2046684D01*
Y2051661D01*
G01X25393Y1301850D02*
X29545D01*
X30535Y1302840D01*
X44074D01*
X52813Y1311579D01*
Y1490739D01*
X40096Y1503456D01*
Y1504534D01*
X40097Y1504535D01*
Y1535166D01*
X78188Y1573257D01*
Y1614347D01*
X73209Y1619326D01*
Y1834036D01*
X93358Y1854185D01*
Y1958343D01*
X32370Y2019331D01*
Y2053056D01*
X28866Y2056560D01*
Y2063151D01*
X31261Y2065546D01*
X38850D01*
X42735Y2061661D01*
G01X33267Y1297913D02*
X45858D01*
X55190Y1307245D01*
X55268D01*
X56293Y1308270D01*
Y1309720D01*
X55413Y1310600D01*
Y1491818D01*
X42697Y1504534D01*
Y1534088D01*
X80788Y1572179D01*
Y1615425D01*
X75809Y1620404D01*
Y1832958D01*
X95958Y1853107D01*
Y1959421D01*
X34970Y2020409D01*
Y2038896D01*
X47735Y2051661D01*
G01X25393Y1293976D02*
X44244D01*
X57593Y1307325D01*
Y1310259D01*
X56713Y1311139D01*
Y1492357D01*
X43997Y1505073D01*
Y1533549D01*
X82088Y1571640D01*
Y1615964D01*
X77109Y1620943D01*
Y1832419D01*
X97258Y1852568D01*
Y1959960D01*
X36270Y2020948D01*
Y2034093D01*
X52735Y2050558D01*
Y2061661D01*
G01X94347Y421562D02*
X105433Y410476D01*
X123681D01*
X128055Y406102D01*
X139920D01*
G01X96510Y1395382D02*
X107199Y1406071D01*
X149773D01*
X156122Y1412420D01*
X322687D01*
X332772Y1422505D01*
Y1425561D01*
X341916Y1434705D01*
X347165D01*
G01X101626Y1397635D02*
X108762Y1404771D01*
X151166D01*
X156962Y1410567D01*
X327941D01*
X345152Y1427778D01*
X350238D01*
X352165Y1429705D01*
G01X347165Y1424705D02*
Y1418313D01*
X339433Y1410581D01*
X334141D01*
X326983Y1403423D01*
X314183D01*
G01X311539Y1753499D02*
X342745Y1784705D01*
X347165D01*
G01X337165Y34705D02*
X346261Y43801D01*
X351543D01*
X359931Y52189D01*
G01X362165Y194705D02*
X361979D01*
X358299Y191025D01*
X339486D01*
X331476Y199035D01*
Y218432D01*
X318088Y231820D01*
G01X320372Y225979D02*
X329742Y216609D01*
Y198221D01*
X338499Y189464D01*
X363804D01*
X367008Y192668D01*
Y197762D01*
X365065Y199705D01*
X357165D01*
G01X314914Y238162D02*
X333694Y219382D01*
Y203176D01*
X337165Y199705D01*
G01X321899Y238137D02*
X338120Y221916D01*
X339856D01*
X357067Y204705D01*
X362165D01*
G01X357165Y209705D02*
X343347Y223523D01*
X339544D01*
X331046Y232021D01*
G01X324709Y231580D02*
X340704Y215585D01*
Y208018D01*
X338911Y206225D01*
Y202774D01*
X342165Y199520D01*
Y194705D01*
G01X363825Y401768D02*
X361967Y399910D01*
X348434D01*
X337165Y388641D01*
Y384705D01*
G01X347165Y374705D02*
X347146Y374686D01*
X342158D01*
X338454Y378390D01*
Y381195D01*
X340810Y383551D01*
Y388842D01*
X349163Y397195D01*
X361794D01*
X368907Y404308D01*
G01X336616Y577978D02*
X341625Y572969D01*
Y558724D01*
X338758Y555857D01*
Y553186D01*
X342166Y549778D01*
Y544705D01*
G01X357166Y549705D02*
X362558D01*
X365498Y546765D01*
Y543217D01*
X361636Y539355D01*
X338618D01*
X329636Y548337D01*
Y584715D01*
G01X362166Y544705D02*
X358163Y540702D01*
X340092D01*
X331867Y548927D01*
Y589810D01*
G01X333750Y595326D02*
Y553121D01*
X337166Y549705D01*
G01X336616Y577978D02*
X336617D01*
G01X337387Y586230D02*
Y582144D01*
X357166Y562365D01*
Y559705D01*
G01X347166Y724705D02*
X347098Y724773D01*
X341864D01*
X338692Y727945D01*
Y731766D01*
X340640Y733714D01*
Y737744D01*
X351018Y748122D01*
X360574D01*
X386790Y774338D01*
G01X362577Y752783D02*
X359807Y750013D01*
X349175D01*
X337166Y738004D01*
Y734705D01*
G01X329938Y948756D02*
Y938026D01*
X326730Y934818D01*
Y928798D01*
X331163Y924365D01*
Y905707D01*
X337165Y899705D01*
G01X318557Y941178D02*
Y929169D01*
X326633Y921093D01*
Y902514D01*
X340041Y889106D01*
X361472D01*
X365636Y893270D01*
Y896725D01*
X362656Y899705D01*
X357165D01*
G01X323868Y929978D02*
Y927737D01*
X328870Y922735D01*
Y902512D01*
X340696Y890686D01*
X358146D01*
X362165Y894705D01*
G01X332527Y943746D02*
Y936475D01*
X335741Y933261D01*
Y924251D01*
X333761Y922271D01*
Y907678D01*
X342165Y899274D01*
Y894705D01*
G01X357165Y909705D02*
Y916257D01*
X336160Y937262D01*
G01X337165Y1084705D02*
Y1100048D01*
X326558Y1110655D01*
Y1126368D01*
G01X328989Y1121090D02*
Y1111592D01*
X342165Y1098416D01*
Y1079705D01*
G01X352165Y1069705D02*
X347363D01*
X343852Y1073216D01*
Y1076151D01*
X345663Y1077962D01*
Y1080567D01*
X343832Y1082398D01*
Y1099991D01*
X331920Y1111903D01*
Y1116088D01*
G01X337509Y1109598D02*
X347165Y1099942D01*
Y1084705D01*
G01X337165Y1249705D02*
X342013D01*
X379335Y1212383D01*
Y1189778D01*
G01X373674Y1199967D02*
Y1208486D01*
X334072Y1248088D01*
Y1260932D01*
X337170Y1264030D01*
X347898D01*
X357223Y1254705D01*
X362165D01*
G01X357165Y1259705D02*
X351540Y1265330D01*
X336520D01*
X332772Y1261582D01*
Y1246592D01*
X371523Y1207841D01*
Y1204725D01*
G01X352165Y1419705D02*
X341008Y1408548D01*
X334395D01*
X327193Y1401346D01*
X319404D01*
G01X325636Y1399114D02*
X328553D01*
X335303Y1405864D01*
X343604D01*
X360704Y1422964D01*
Y1426708D01*
X354590Y1432822D01*
X350311D01*
X348324Y1430835D01*
X345534D01*
X344404Y1429705D01*
X342165D01*
G01X350690Y1403207D02*
X365710Y1418227D01*
Y1431598D01*
X358067Y1439241D01*
X341701D01*
X337165Y1434705D01*
G01X362165Y1604705D02*
Y1609452D01*
X355275Y1616342D01*
X334832D01*
X330324Y1611834D01*
Y1585158D01*
X343402Y1572080D01*
G01X348710Y1570187D02*
X332697Y1586200D01*
Y1610851D01*
X335815Y1613969D01*
X352901D01*
X357165Y1609705D01*
G01X348245Y1575241D02*
X337165Y1586321D01*
Y1599705D01*
G01X329887Y1752081D02*
X347165Y1769359D01*
Y1774705D01*
G01X321283Y1753466D02*
X347522Y1779705D01*
X352165D01*
G01X335730Y1753270D02*
X352165Y1769705D01*
G01X357165Y1959705D02*
X353396Y1963474D01*
X336515D01*
X333460Y1960419D01*
Y1948214D01*
X363361Y1918313D01*
G01X362165Y1954705D02*
Y1960038D01*
X356818Y1965385D01*
X336057D01*
X331854Y1961182D01*
Y1947144D01*
X358318Y1920680D01*
G01X369748Y1921795D02*
X341838Y1949705D01*
X337165D01*
G01X379572Y58441D02*
X361300Y40169D01*
X358097D01*
X352165Y34237D01*
Y29705D01*
G01X365720Y52336D02*
X353628Y40244D01*
X347789D01*
X343928Y36383D01*
Y32830D01*
X345839Y30919D01*
Y28360D01*
X343546Y26067D01*
Y23545D01*
X347386Y19705D01*
X352165D01*
G01X379257Y52148D02*
X351814Y24705D01*
X347165D01*
G01X342165Y29705D02*
Y36912D01*
X347411Y42158D01*
X352835D01*
X387524Y76847D01*
G01X372204Y56126D02*
X350783Y34705D01*
X347165D01*
G01X352165Y369705D02*
Y374375D01*
X343863Y382677D01*
Y386061D01*
X351424Y393622D01*
X364129D01*
X380619Y410112D01*
G01X374442Y406857D02*
X362987Y395402D01*
X349235D01*
X342165Y388332D01*
Y379705D01*
G01X380878Y403999D02*
X366730Y389851D01*
X356855D01*
X352165Y385161D01*
Y379705D01*
G01X374542Y401282D02*
X365206Y391946D01*
X354406D01*
X347165Y384705D01*
G01X362166Y554705D02*
Y560860D01*
X342900Y580126D01*
G01X382892Y767710D02*
X361508Y746326D01*
X351743D01*
X342166Y736749D01*
Y729705D01*
G01X352166D02*
Y735881D01*
X357100Y740815D01*
X366114D01*
X391278Y765979D01*
G01X352166Y719705D02*
Y724855D01*
X343861Y733160D01*
Y736061D01*
X352218Y744418D01*
X362862D01*
X380186Y761742D01*
G01X347166Y734705D02*
X355095Y742634D01*
X364540D01*
X376654Y754748D01*
G01X343656Y933725D02*
X362165Y915216D01*
Y904705D01*
G01X344099Y1106798D02*
X350539Y1100358D01*
Y1083109D01*
X347165Y1079735D01*
Y1074705D01*
G01X352165Y1079705D02*
Y1101992D01*
X349855Y1104302D01*
G01X376472Y1194999D02*
Y1210410D01*
X345372Y1241498D01*
X342165Y1244705D01*
G01X362165D02*
X383276Y1223594D01*
Y1184136D01*
G01X357165Y1249705D02*
X363021D01*
X386816Y1225910D01*
Y1179841D01*
G01X350690Y1403243D02*
Y1403207D01*
G01X357165Y1599705D02*
Y1572736D01*
X361011Y1568890D01*
G01X342165Y1594705D02*
Y1584189D01*
X355364Y1570990D01*
G01X362165Y1594705D02*
Y1571772D01*
X367829Y1566108D01*
G01X374775Y1919243D02*
X357165Y1936853D01*
Y1949705D01*
G01X342165Y1944705D02*
X363411Y1923459D01*
G01X379403Y1917261D02*
X362165Y1934499D01*
Y1944705D01*
G01X379257Y52158D02*
Y52148D01*
G01X391278Y765979D02*
Y765894D01*
M02*
